FILE_TYPE = MACRO_DRAWING;
SET COLOR_WIRE YELLOW;
SET COLOR_PROP ORANGE;
SET COLOR_DOT WHITE;
SET COLOR_ARC YELLOW;
SET COLOR_BODY GREEN;
SET COLOR_NOTE PURPLE;
SET PROP_DISPLAY VALUE;
SET PAGE_NUMBER P76;
FORCEADD OFFPAGE..2
R 2
(-3125 5450);
FORCEPROP 2 LAST $XR1 117 
J 0
(-3499 5450);
DISPLAY 0.638298 (-3499 5450);
PAINT MONO (-3499 5450);
FORCEPROP 2 LAST $XR0 76 
J 0
(-3379 5450);
DISPLAY 0.638298 (-3379 5450);
PAINT MONO (-3379 5450);
FORCEPROP 2 LAST CDS_LIB standard
J 2
(-3125 5450);
DISPLAY INVISIBLE (-3125 5450);
FORCEPROP 1 LAST OFFPAGE TRUE
J 2
(-3450 5325);
DISPLAY 0.872340 (-3450 5325);
PAINT GREEN (-3450 5325);
DISPLAY INVISIBLE (-3450 5325);
FORCEPROP 1 LAST COMMENT_BODY TRUE
J 2
(-3080 5355);
DISPLAY 0.872340 (-3080 5355);
PAINT PEACH (-3080 5355);
DISPLAY INVISIBLE (-3080 5355);
FORCEPROP 2 LAST PATH I100
J 0
(-3375 5500);
DISPLAY 1.021277 (-3375 5500);
DISPLAY INVISIBLE (-3375 5500);
FORCEADD OFFPAGE..2
R 2
(-3125 5250);
FORCEPROP 2 LAST $XR1 117 
J 0
(-3499 5250);
DISPLAY 0.638298 (-3499 5250);
PAINT MONO (-3499 5250);
FORCEPROP 2 LAST $XR0 76 
J 0
(-3379 5250);
DISPLAY 0.638298 (-3379 5250);
PAINT MONO (-3379 5250);
FORCEPROP 2 LAST CDS_LIB standard
J 2
(-3125 5250);
DISPLAY INVISIBLE (-3125 5250);
FORCEPROP 1 LAST OFFPAGE TRUE
J 2
(-3450 5125);
DISPLAY 0.872340 (-3450 5125);
PAINT GREEN (-3450 5125);
DISPLAY INVISIBLE (-3450 5125);
FORCEPROP 1 LAST COMMENT_BODY TRUE
J 2
(-3080 5155);
DISPLAY 0.872340 (-3080 5155);
PAINT PEACH (-3080 5155);
DISPLAY INVISIBLE (-3080 5155);
FORCEPROP 2 LAST PATH I101
J 0
(-3375 5300);
DISPLAY 1.021277 (-3375 5300);
DISPLAY INVISIBLE (-3375 5300);
FORCEADD OFFPAGE..2
R 2
(-3125 5200);
FORCEPROP 2 LAST $XR1 117 
J 0
(-3499 5200);
DISPLAY 0.638298 (-3499 5200);
PAINT MONO (-3499 5200);
FORCEPROP 2 LAST $XR0 76 
J 0
(-3379 5200);
DISPLAY 0.638298 (-3379 5200);
PAINT MONO (-3379 5200);
FORCEPROP 2 LAST CDS_LIB standard
J 2
(-3125 5200);
DISPLAY INVISIBLE (-3125 5200);
FORCEPROP 2 LAST PATH I102
J 0
(-3375 5250);
DISPLAY 1.021277 (-3375 5250);
DISPLAY INVISIBLE (-3375 5250);
FORCEPROP 1 LAST COMMENT_BODY TRUE
J 2
(-3080 5105);
DISPLAY 0.872340 (-3080 5105);
PAINT PEACH (-3080 5105);
DISPLAY INVISIBLE (-3080 5105);
FORCEPROP 1 LAST OFFPAGE TRUE
J 2
(-3450 5075);
DISPLAY 0.872340 (-3450 5075);
PAINT GREEN (-3450 5075);
DISPLAY INVISIBLE (-3450 5075);
FORCEADD OFFPAGE..3
R 2
(-3125 5350);
FORCEPROP 2 LAST $XR1 117 
J 0
(-3494 5350);
DISPLAY 0.638298 (-3494 5350);
PAINT MONO (-3494 5350);
FORCEPROP 2 LAST $XR0 76 
J 0
(-3374 5350);
DISPLAY 0.638298 (-3374 5350);
PAINT MONO (-3374 5350);
FORCEPROP 2 LAST CDS_LIB standard
J 0
(-3125 5350);
DISPLAY INVISIBLE (-3125 5350);
FORCEPROP 1 LAST OFFPAGE TRUE
J 2
(-3450 5225);
DISPLAY 0.872340 (-3450 5225);
PAINT GREEN (-3450 5225);
DISPLAY INVISIBLE (-3450 5225);
FORCEPROP 1 LAST COMMENT_BODY TRUE
J 2
(-3075 5250);
DISPLAY 0.872340 (-3075 5250);
PAINT PEACH (-3075 5250);
DISPLAY INVISIBLE (-3075 5250);
FORCEPROP 2 LAST PATH I103
J 0
(-3350 5400);
DISPLAY 1.021277 (-3350 5400);
DISPLAY INVISIBLE (-3350 5400);
FORCEADD OFFPAGE..3
R 2
(-3125 5300);
FORCEPROP 2 LAST $XR1 117 
J 0
(-3494 5300);
DISPLAY 0.638298 (-3494 5300);
PAINT MONO (-3494 5300);
FORCEPROP 2 LAST $XR0 76 
J 0
(-3374 5300);
DISPLAY 0.638298 (-3374 5300);
PAINT MONO (-3374 5300);
FORCEPROP 2 LAST CDS_LIB standard
J 0
(-3125 5300);
DISPLAY INVISIBLE (-3125 5300);
FORCEPROP 1 LAST OFFPAGE TRUE
J 2
(-3450 5175);
DISPLAY 0.872340 (-3450 5175);
PAINT GREEN (-3450 5175);
DISPLAY INVISIBLE (-3450 5175);
FORCEPROP 1 LAST COMMENT_BODY TRUE
J 2
(-3075 5200);
DISPLAY 0.872340 (-3075 5200);
PAINT PEACH (-3075 5200);
DISPLAY INVISIBLE (-3075 5200);
FORCEPROP 2 LAST PATH I104
J 0
(-3350 5350);
DISPLAY 1.021277 (-3350 5350);
DISPLAY INVISIBLE (-3350 5350);
FORCEADD UNIVERSAL_POWER..1
(-8025 6075);
FORCEPROP 3 LASTPIN (-8025 6025) SIG_NAME PVDD18_S5_P0\g
J 0
(-8015 6035);
DISPLAY 0.659574 (-8015 6035);
PAINT MONO (-8015 6035);
DISPLAY INVISIBLE (-8015 6035);
FORCEPROP 1 LAST HDL_POWER PVDD18_S5_P0
J 1
(-8025 6125);
DISPLAY 0.489362 (-8025 6125);
PAINT GREEN (-8025 6125);
FORCEPROP 2 LAST CDS_LIB pure_quanta_power
J 0
(-8025 6075);
DISPLAY INVISIBLE (-8025 6075);
FORCEPROP 1 LAST PATH I105
J 0
(-7975 6100);
DISPLAY 0.872340 (-7975 6100);
PAINT AQUA (-7975 6100);
DISPLAY INVISIBLE (-7975 6100);
FORCEADD Q_RES..2
(-8025 5875);
FORCEPROP 1 LAST LOCATION R811
J 0
(-8000 5750);
DISPLAY 0.489362 (-8000 5750);
PAINT SKYBLUE (-8000 5750);
FORCEPROP 2 LAST $SEC 1
J 0
(-7975 6100);
DISPLAY 0.680851 (-7975 6100);
PAINT MONO (-7975 6100);
DISPLAY INVISIBLE (-7975 6100);
FORCEPROP 2 LAST CDS_SEC 1
J 0
(-7975 6100);
DISPLAY 0.680851 (-7975 6100);
DISPLAY INVISIBLE (-7975 6100);
FORCEPROP 1 LASTPIN (-8025 5975) $PN 1
J 0
(-8020 5937);
DISPLAY 0.489362 (-8020 5937);
PAINT MONO (-8020 5937);
FORCEPROP 1 LASTPIN (-8025 5775) $PN 2
J 0
(-8020 5785);
DISPLAY 0.489362 (-8020 5785);
PAINT MONO (-8020 5785);
FORCEPROP 1 LAST MATERIAL CHIP
J 0
(-7985 5800);
DISPLAY 0.489362 (-7985 5800);
PAINT SKYBLUE (-7985 5800);
FORCEPROP 1 LAST WATTAGE 1/16W
J 0
(-7985 5850);
DISPLAY 0.489362 (-7985 5850);
PAINT SKYBLUE (-7985 5850);
FORCEPROP 1 LAST VALUE 1K
J 0
(-7980 5950);
DISPLAY 0.489362 (-7980 5950);
PAINT SKYBLUE (-7980 5950);
FORCEPROP 1 LAST TOLERANCE 5%
J 0
(-7980 5900);
DISPLAY 0.489362 (-7980 5900);
PAINT SKYBLUE (-7980 5900);
FORCEPROP 2 LAST CDS_LIB pure_quanta
J 0
(-8025 5875);
DISPLAY INVISIBLE (-8025 5875);
FORCEPROP 1 LAST PATH I106
J 0
(-7975 6050);
DISPLAY 0.978723 (-7975 6050);
PAINT WHITE (-7975 6050);
DISPLAY INVISIBLE (-7975 6050);
FORCEPROP 1 LAST PART_NUMBER TMP_QCS21002JB34
J 0
(-7985 5750);
DISPLAY 0.489362 (-7985 5750);
PAINT SKYBLUE (-7985 5750);
DISPLAY INVISIBLE (-7985 5750);
FORCEPROP 1 LAST PACK_TYPE 0402LF
J 0
(-7975 5750);
DISPLAY 0.382979 (-7975 5750);
PAINT SKYBLUE (-7975 5750);
DISPLAY INVISIBLE (-7975 5750);
FORCEADD Q_RES..2
(-8200 5875);
FORCEPROP 1 LAST LOCATION R659
J 0
(-8175 5750);
DISPLAY 0.489362 (-8175 5750);
PAINT SKYBLUE (-8175 5750);
FORCEPROP 2 LAST $SEC 1
J 0
(-8150 6100);
DISPLAY 0.680851 (-8150 6100);
PAINT MONO (-8150 6100);
DISPLAY INVISIBLE (-8150 6100);
FORCEPROP 2 LAST CDS_SEC 1
J 0
(-8150 6100);
DISPLAY 0.680851 (-8150 6100);
DISPLAY INVISIBLE (-8150 6100);
FORCEPROP 1 LASTPIN (-8200 5975) $PN 1
J 0
(-8195 5937);
DISPLAY 0.489362 (-8195 5937);
PAINT MONO (-8195 5937);
FORCEPROP 1 LASTPIN (-8200 5775) $PN 2
J 0
(-8195 5785);
DISPLAY 0.489362 (-8195 5785);
PAINT MONO (-8195 5785);
FORCEPROP 1 LAST TOLERANCE 5%
J 0
(-8155 5900);
DISPLAY 0.489362 (-8155 5900);
PAINT SKYBLUE (-8155 5900);
FORCEPROP 1 LAST WATTAGE 1/16W
J 0
(-8160 5850);
DISPLAY 0.489362 (-8160 5850);
PAINT SKYBLUE (-8160 5850);
FORCEPROP 1 LAST MATERIAL CHIP
J 0
(-8160 5800);
DISPLAY 0.489362 (-8160 5800);
PAINT SKYBLUE (-8160 5800);
FORCEPROP 1 LAST VALUE 1K
J 0
(-8155 5950);
DISPLAY 0.489362 (-8155 5950);
PAINT SKYBLUE (-8155 5950);
FORCEPROP 2 LAST CDS_LIB pure_quanta
J 0
(-8200 5875);
DISPLAY INVISIBLE (-8200 5875);
FORCEPROP 1 LAST PATH I107
J 0
(-8150 6050);
DISPLAY 0.978723 (-8150 6050);
PAINT WHITE (-8150 6050);
DISPLAY INVISIBLE (-8150 6050);
FORCEPROP 1 LAST PART_NUMBER TMP_QCS21002JB34
J 0
(-8160 5750);
DISPLAY 0.489362 (-8160 5750);
PAINT SKYBLUE (-8160 5750);
DISPLAY INVISIBLE (-8160 5750);
FORCEPROP 1 LAST PACK_TYPE 0402LF
J 0
(-8150 5750);
DISPLAY 0.382979 (-8150 5750);
PAINT SKYBLUE (-8150 5750);
DISPLAY INVISIBLE (-8150 5750);
FORCEADD Q_RES..2
(-8375 5875);
FORCEPROP 1 LAST LOCATION R601
J 0
(-8350 5750);
DISPLAY 0.489362 (-8350 5750);
PAINT SKYBLUE (-8350 5750);
FORCEPROP 2 LAST $SEC 1
J 0
(-8325 6100);
DISPLAY 0.680851 (-8325 6100);
PAINT MONO (-8325 6100);
DISPLAY INVISIBLE (-8325 6100);
FORCEPROP 2 LAST CDS_SEC 1
J 0
(-8325 6100);
DISPLAY 0.680851 (-8325 6100);
DISPLAY INVISIBLE (-8325 6100);
FORCEPROP 1 LASTPIN (-8375 5975) $PN 1
J 0
(-8370 5937);
DISPLAY 0.489362 (-8370 5937);
PAINT MONO (-8370 5937);
FORCEPROP 1 LASTPIN (-8375 5775) $PN 2
J 0
(-8370 5785);
DISPLAY 0.489362 (-8370 5785);
PAINT MONO (-8370 5785);
FORCEPROP 1 LAST MATERIAL CHIP
J 0
(-8335 5800);
DISPLAY 0.489362 (-8335 5800);
PAINT SKYBLUE (-8335 5800);
FORCEPROP 1 LAST WATTAGE 1/16W
J 0
(-8335 5850);
DISPLAY 0.489362 (-8335 5850);
PAINT SKYBLUE (-8335 5850);
FORCEPROP 1 LAST TOLERANCE 5%
J 0
(-8330 5900);
DISPLAY 0.489362 (-8330 5900);
PAINT SKYBLUE (-8330 5900);
FORCEPROP 1 LAST VALUE 1K
J 0
(-8330 5950);
DISPLAY 0.489362 (-8330 5950);
PAINT SKYBLUE (-8330 5950);
FORCEPROP 2 LAST CDS_LIB pure_quanta
J 0
(-8375 5875);
DISPLAY INVISIBLE (-8375 5875);
FORCEPROP 1 LAST PATH I108
J 0
(-8325 6050);
DISPLAY 0.978723 (-8325 6050);
PAINT WHITE (-8325 6050);
DISPLAY INVISIBLE (-8325 6050);
FORCEPROP 1 LAST PART_NUMBER TMP_QCS21002JB34
J 0
(-8335 5750);
DISPLAY 0.489362 (-8335 5750);
PAINT SKYBLUE (-8335 5750);
DISPLAY INVISIBLE (-8335 5750);
FORCEPROP 1 LAST PACK_TYPE 0402LF
J 0
(-8325 5750);
DISPLAY 0.382979 (-8325 5750);
PAINT SKYBLUE (-8325 5750);
DISPLAY INVISIBLE (-8325 5750);
FORCEADD OFFPAGE..2
(-7100 5575);
FORCEPROP 2 LAST $XR1 76 
J 0
(-6821 5575);
DISPLAY 0.638298 (-6821 5575);
PAINT MONO (-6821 5575);
FORCEPROP 2 LAST $XR0 29 
J 0
(-6911 5575);
DISPLAY 0.638298 (-6911 5575);
PAINT MONO (-6911 5575);
FORCEPROP 2 LAST CDS_LIB standard
J 0
(-7100 5575);
DISPLAY INVISIBLE (-7100 5575);
FORCEPROP 1 LAST OFFPAGE TRUE
J 0
(-6775 5450);
DISPLAY 0.872340 (-6775 5450);
PAINT GREEN (-6775 5450);
DISPLAY INVISIBLE (-6775 5450);
FORCEPROP 1 LAST COMMENT_BODY TRUE
J 0
(-7145 5480);
DISPLAY 0.872340 (-7145 5480);
PAINT PEACH (-7145 5480);
DISPLAY INVISIBLE (-7145 5480);
FORCEPROP 2 LAST PATH I109
J 0
(-6925 5650);
DISPLAY 1.021277 (-6925 5650);
DISPLAY INVISIBLE (-6925 5650);
FORCEADD OFFPAGE..2
(-7100 5525);
FORCEPROP 2 LAST $XR1 76 
J 0
(-6821 5525);
DISPLAY 0.638298 (-6821 5525);
PAINT MONO (-6821 5525);
FORCEPROP 2 LAST $XR0 29 
J 0
(-6911 5525);
DISPLAY 0.638298 (-6911 5525);
PAINT MONO (-6911 5525);
FORCEPROP 2 LAST CDS_LIB standard
J 0
(-7100 5525);
DISPLAY INVISIBLE (-7100 5525);
FORCEPROP 1 LAST OFFPAGE TRUE
J 0
(-6775 5400);
DISPLAY 0.872340 (-6775 5400);
PAINT GREEN (-6775 5400);
DISPLAY INVISIBLE (-6775 5400);
FORCEPROP 1 LAST COMMENT_BODY TRUE
J 0
(-7145 5430);
DISPLAY 0.872340 (-7145 5430);
PAINT PEACH (-7145 5430);
DISPLAY INVISIBLE (-7145 5430);
FORCEPROP 2 LAST PATH I110
J 0
(-6925 5600);
DISPLAY 1.021277 (-6925 5600);
DISPLAY INVISIBLE (-6925 5600);
FORCEADD OFFPAGE..2
(-7100 5475);
FORCEPROP 2 LAST $XR1 76 
J 0
(-6821 5475);
DISPLAY 0.638298 (-6821 5475);
PAINT MONO (-6821 5475);
FORCEPROP 2 LAST $XR0 29 
J 0
(-6911 5475);
DISPLAY 0.638298 (-6911 5475);
PAINT MONO (-6911 5475);
FORCEPROP 2 LAST CDS_LIB standard
J 0
(-7100 5475);
DISPLAY INVISIBLE (-7100 5475);
FORCEPROP 1 LAST OFFPAGE TRUE
J 0
(-6775 5350);
DISPLAY 0.872340 (-6775 5350);
PAINT GREEN (-6775 5350);
DISPLAY INVISIBLE (-6775 5350);
FORCEPROP 1 LAST COMMENT_BODY TRUE
J 0
(-7145 5380);
DISPLAY 0.872340 (-7145 5380);
PAINT PEACH (-7145 5380);
DISPLAY INVISIBLE (-7145 5380);
FORCEPROP 2 LAST PATH I111
J 0
(-6925 5550);
DISPLAY 1.021277 (-6925 5550);
DISPLAY INVISIBLE (-6925 5550);
FORCEADD Q_RES..2
R 2
(-2225 5625);
FORCEPROP 1 LAST LOCATION R20
J 0
(-2200 5725);
DISPLAY 0.489362 (-2200 5725);
PAINT SKYBLUE (-2200 5725);
FORCEPROP 0 LAST $SEC 1
J 0
(-2200 5750);
DISPLAY 0.680851 (-2200 5750);
PAINT MONO (-2200 5750);
DISPLAY INVISIBLE (-2200 5750);
FORCEPROP 0 LAST CDS_SEC 1
J 0
(-2200 5750);
DISPLAY 0.680851 (-2200 5750);
DISPLAY INVISIBLE (-2200 5750);
FORCEPROP 1 LASTPIN (-2225 5725) $PN 1
J 2
(-2230 5687);
DISPLAY 0.489362 (-2230 5687);
PAINT MONO (-2230 5687);
FORCEPROP 1 LASTPIN (-2225 5525) $PN 2
J 2
(-2230 5535);
DISPLAY 0.489362 (-2230 5535);
PAINT MONO (-2230 5535);
FORCEPROP 1 LAST VALUE 10K
J 0
(-2200 5675);
DISPLAY 0.489362 (-2200 5675);
PAINT SKYBLUE (-2200 5675);
FORCEPROP 1 LAST TOLERANCE 1%
J 0
(-2200 5625);
DISPLAY 0.489362 (-2200 5625);
PAINT SKYBLUE (-2200 5625);
FORCEPROP 1 LAST MATERIAL CHIP
J 0
(-2200 5575);
DISPLAY 0.489362 (-2200 5575);
PAINT SKYBLUE (-2200 5575);
FORCEPROP 1 LAST PART_NUMBER CS31002FB08
J 2
(-2275 5550);
DISPLAY 0.489362 (-2275 5550);
PAINT SKYBLUE (-2275 5550);
DISPLAY INVISIBLE (-2275 5550);
FORCEPROP 1 LAST PACK_TYPE 0402LF
J 2
(-2275 5575);
DISPLAY 0.489362 (-2275 5575);
PAINT SKYBLUE (-2275 5575);
DISPLAY INVISIBLE (-2275 5575);
FORCEPROP 1 LAST WATTAGE 1/16W
J 2
(-2275 5625);
DISPLAY 0.489362 (-2275 5625);
PAINT SKYBLUE (-2275 5625);
DISPLAY INVISIBLE (-2275 5625);
FORCEPROP 1 LAST PATH I115
J 2
(-2275 5800);
DISPLAY 0.978723 (-2275 5800);
PAINT WHITE (-2275 5800);
DISPLAY INVISIBLE (-2275 5800);
FORCEPROP 2 LAST CDS_LIB pure_quanta
J 0
(-2225 5625);
DISPLAY INVISIBLE (-2225 5625);
FORCEADD Q_RES..2
R 2
(-1875 5625);
FORCEPROP 1 LAST LOCATION R21
J 0
(-1850 5725);
DISPLAY 0.489362 (-1850 5725);
PAINT SKYBLUE (-1850 5725);
FORCEPROP 0 LAST $SEC 1
J 0
(-1850 5750);
DISPLAY 0.680851 (-1850 5750);
PAINT MONO (-1850 5750);
DISPLAY INVISIBLE (-1850 5750);
FORCEPROP 0 LAST CDS_SEC 1
J 0
(-1850 5750);
DISPLAY 0.680851 (-1850 5750);
DISPLAY INVISIBLE (-1850 5750);
FORCEPROP 1 LASTPIN (-1875 5725) $PN 1
J 2
(-1880 5687);
DISPLAY 0.489362 (-1880 5687);
PAINT MONO (-1880 5687);
FORCEPROP 1 LASTPIN (-1875 5525) $PN 2
J 2
(-1880 5535);
DISPLAY 0.489362 (-1880 5535);
PAINT MONO (-1880 5535);
FORCEPROP 1 LAST TOLERANCE 5%
J 0
(-1850 5625);
DISPLAY 0.489362 (-1850 5625);
PAINT SKYBLUE (-1850 5625);
FORCEPROP 1 LAST VALUE 1K
J 0
(-1850 5675);
DISPLAY 0.489362 (-1850 5675);
PAINT SKYBLUE (-1850 5675);
FORCEPROP 1 LAST MATERIAL EMPTY
J 0
(-1850 5575);
DISPLAY 0.489362 (-1850 5575);
PAINT RED (-1850 5575);
FORCEPROP 1 LAST PACK_TYPE 0402LF
J 2
(-1925 5575);
DISPLAY 0.489362 (-1925 5575);
PAINT SKYBLUE (-1925 5575);
DISPLAY INVISIBLE (-1925 5575);
FORCEPROP 1 LAST PART_NUMBER TMP_QCS21002JB34
J 2
(-1925 5550);
DISPLAY 0.489362 (-1925 5550);
PAINT SKYBLUE (-1925 5550);
DISPLAY INVISIBLE (-1925 5550);
FORCEPROP 1 LAST WATTAGE 1/16W
J 2
(-1925 5625);
DISPLAY 0.489362 (-1925 5625);
PAINT SKYBLUE (-1925 5625);
DISPLAY INVISIBLE (-1925 5625);
FORCEPROP 1 LAST PATH I116
J 2
(-1925 5800);
DISPLAY 0.978723 (-1925 5800);
PAINT WHITE (-1925 5800);
DISPLAY INVISIBLE (-1925 5800);
FORCEPROP 2 LAST CDS_LIB pure_quanta
J 0
(-1875 5625);
DISPLAY INVISIBLE (-1875 5625);
FORCEADD Q_RES..2
R 2
(-1700 5625);
FORCEPROP 1 LAST LOCATION R127
J 0
(-1675 5725);
DISPLAY 0.489362 (-1675 5725);
PAINT SKYBLUE (-1675 5725);
FORCEPROP 0 LAST $SEC 1
J 0
(-1675 5750);
DISPLAY 0.680851 (-1675 5750);
PAINT MONO (-1675 5750);
DISPLAY INVISIBLE (-1675 5750);
FORCEPROP 0 LAST CDS_SEC 1
J 0
(-1675 5750);
DISPLAY 0.680851 (-1675 5750);
DISPLAY INVISIBLE (-1675 5750);
FORCEPROP 1 LASTPIN (-1700 5725) $PN 1
J 2
(-1705 5687);
DISPLAY 0.489362 (-1705 5687);
PAINT MONO (-1705 5687);
FORCEPROP 1 LASTPIN (-1700 5525) $PN 2
J 2
(-1705 5535);
DISPLAY 0.489362 (-1705 5535);
PAINT MONO (-1705 5535);
FORCEPROP 1 LAST VALUE 1K
J 0
(-1675 5675);
DISPLAY 0.489362 (-1675 5675);
PAINT SKYBLUE (-1675 5675);
FORCEPROP 1 LAST TOLERANCE 5%
J 0
(-1675 5625);
DISPLAY 0.489362 (-1675 5625);
PAINT SKYBLUE (-1675 5625);
FORCEPROP 1 LAST MATERIAL EMPTY
J 0
(-1675 5575);
DISPLAY 0.489362 (-1675 5575);
PAINT RED (-1675 5575);
FORCEPROP 1 LAST PACK_TYPE 0402LF
J 2
(-1750 5575);
DISPLAY 0.489362 (-1750 5575);
PAINT SKYBLUE (-1750 5575);
DISPLAY INVISIBLE (-1750 5575);
FORCEPROP 1 LAST PART_NUMBER TMP_QCS21002JB34
J 2
(-1750 5550);
DISPLAY 0.489362 (-1750 5550);
PAINT SKYBLUE (-1750 5550);
DISPLAY INVISIBLE (-1750 5550);
FORCEPROP 1 LAST WATTAGE 1/16W
J 2
(-1750 5625);
DISPLAY 0.489362 (-1750 5625);
PAINT SKYBLUE (-1750 5625);
DISPLAY INVISIBLE (-1750 5625);
FORCEPROP 1 LAST PATH I117
J 2
(-1750 5800);
DISPLAY 0.978723 (-1750 5800);
PAINT WHITE (-1750 5800);
DISPLAY INVISIBLE (-1750 5800);
FORCEPROP 2 LAST CDS_LIB pure_quanta
J 0
(-1700 5625);
DISPLAY INVISIBLE (-1700 5625);
FORCEADD Q_RES..2
R 2
(-1525 5625);
FORCEPROP 1 LAST LOCATION R128
J 0
(-1500 5725);
DISPLAY 0.489362 (-1500 5725);
PAINT SKYBLUE (-1500 5725);
FORCEPROP 0 LAST $SEC 1
J 0
(-1500 5750);
DISPLAY 0.680851 (-1500 5750);
PAINT MONO (-1500 5750);
DISPLAY INVISIBLE (-1500 5750);
FORCEPROP 0 LAST CDS_SEC 1
J 0
(-1500 5750);
DISPLAY 0.680851 (-1500 5750);
DISPLAY INVISIBLE (-1500 5750);
FORCEPROP 1 LASTPIN (-1525 5725) $PN 1
J 2
(-1530 5687);
DISPLAY 0.489362 (-1530 5687);
PAINT MONO (-1530 5687);
FORCEPROP 1 LASTPIN (-1525 5525) $PN 2
J 2
(-1530 5535);
DISPLAY 0.489362 (-1530 5535);
PAINT MONO (-1530 5535);
FORCEPROP 1 LAST VALUE 1K
J 0
(-1500 5675);
DISPLAY 0.489362 (-1500 5675);
PAINT SKYBLUE (-1500 5675);
FORCEPROP 1 LAST TOLERANCE 5%
J 0
(-1500 5625);
DISPLAY 0.489362 (-1500 5625);
PAINT SKYBLUE (-1500 5625);
FORCEPROP 1 LAST MATERIAL EMPTY
J 0
(-1500 5575);
DISPLAY 0.489362 (-1500 5575);
PAINT RED (-1500 5575);
FORCEPROP 1 LAST PACK_TYPE 0402LF
J 2
(-1575 5575);
DISPLAY 0.489362 (-1575 5575);
PAINT SKYBLUE (-1575 5575);
DISPLAY INVISIBLE (-1575 5575);
FORCEPROP 1 LAST PART_NUMBER TMP_QCS21002JB34
J 2
(-1575 5550);
DISPLAY 0.489362 (-1575 5550);
PAINT SKYBLUE (-1575 5550);
DISPLAY INVISIBLE (-1575 5550);
FORCEPROP 1 LAST WATTAGE 1/16W
J 2
(-1575 5625);
DISPLAY 0.489362 (-1575 5625);
PAINT SKYBLUE (-1575 5625);
DISPLAY INVISIBLE (-1575 5625);
FORCEPROP 1 LAST PATH I118
J 2
(-1575 5800);
DISPLAY 0.978723 (-1575 5800);
PAINT WHITE (-1575 5800);
DISPLAY INVISIBLE (-1575 5800);
FORCEPROP 2 LAST CDS_LIB pure_quanta
J 0
(-1525 5625);
DISPLAY INVISIBLE (-1525 5625);
FORCEADD Q_RES..2
R 2
(-1350 5625);
FORCEPROP 1 LAST LOCATION R129
J 0
(-1325 5725);
DISPLAY 0.489362 (-1325 5725);
PAINT SKYBLUE (-1325 5725);
FORCEPROP 0 LAST $SEC 1
J 0
(-1325 5750);
DISPLAY 0.680851 (-1325 5750);
PAINT MONO (-1325 5750);
DISPLAY INVISIBLE (-1325 5750);
FORCEPROP 0 LAST CDS_SEC 1
J 0
(-1325 5750);
DISPLAY 0.680851 (-1325 5750);
DISPLAY INVISIBLE (-1325 5750);
FORCEPROP 1 LASTPIN (-1350 5725) $PN 1
J 2
(-1355 5687);
DISPLAY 0.489362 (-1355 5687);
PAINT MONO (-1355 5687);
FORCEPROP 1 LASTPIN (-1350 5525) $PN 2
J 2
(-1355 5535);
DISPLAY 0.489362 (-1355 5535);
PAINT MONO (-1355 5535);
FORCEPROP 1 LAST VALUE 1K
J 0
(-1325 5675);
DISPLAY 0.489362 (-1325 5675);
PAINT SKYBLUE (-1325 5675);
FORCEPROP 1 LAST TOLERANCE 5%
J 0
(-1325 5625);
DISPLAY 0.489362 (-1325 5625);
PAINT SKYBLUE (-1325 5625);
FORCEPROP 1 LAST MATERIAL EMPTY
J 0
(-1325 5575);
DISPLAY 0.489362 (-1325 5575);
PAINT RED (-1325 5575);
FORCEPROP 1 LAST WATTAGE 1/16W
J 2
(-1400 5625);
DISPLAY 0.489362 (-1400 5625);
PAINT SKYBLUE (-1400 5625);
DISPLAY INVISIBLE (-1400 5625);
FORCEPROP 1 LAST PART_NUMBER TMP_QCS21002JB34
J 2
(-1400 5550);
DISPLAY 0.489362 (-1400 5550);
PAINT SKYBLUE (-1400 5550);
DISPLAY INVISIBLE (-1400 5550);
FORCEPROP 1 LAST PACK_TYPE 0402LF
J 2
(-1400 5575);
DISPLAY 0.489362 (-1400 5575);
PAINT SKYBLUE (-1400 5575);
DISPLAY INVISIBLE (-1400 5575);
FORCEPROP 1 LAST PATH I119
J 2
(-1400 5800);
DISPLAY 0.978723 (-1400 5800);
PAINT WHITE (-1400 5800);
DISPLAY INVISIBLE (-1400 5800);
FORCEPROP 2 LAST CDS_LIB pure_quanta
J 0
(-1350 5625);
DISPLAY INVISIBLE (-1350 5625);
FORCEADD OFFPAGE..2
(-7100 5425);
FORCEPROP 2 LAST $XR1 76 
J 0
(-6821 5425);
DISPLAY 0.638298 (-6821 5425);
PAINT MONO (-6821 5425);
FORCEPROP 2 LAST $XR0 29 
J 0
(-6911 5425);
DISPLAY 0.638298 (-6911 5425);
PAINT MONO (-6911 5425);
FORCEPROP 2 LAST CDS_LIB standard
J 0
(-7100 5425);
DISPLAY INVISIBLE (-7100 5425);
FORCEPROP 1 LAST OFFPAGE TRUE
J 0
(-6775 5300);
DISPLAY 0.872340 (-6775 5300);
PAINT GREEN (-6775 5300);
DISPLAY INVISIBLE (-6775 5300);
FORCEPROP 1 LAST COMMENT_BODY TRUE
J 0
(-7145 5330);
DISPLAY 0.872340 (-7145 5330);
PAINT PEACH (-7145 5330);
DISPLAY INVISIBLE (-7145 5330);
FORCEPROP 2 LAST PATH I127
J 0
(-6925 5500);
DISPLAY 0.680851 (-6925 5500);
DISPLAY INVISIBLE (-6925 5500);
FORCEADD OFFPAGE..2
(-7100 5375);
FORCEPROP 2 LAST $XR1 76 
J 0
(-6821 5375);
DISPLAY 0.638298 (-6821 5375);
PAINT MONO (-6821 5375);
FORCEPROP 2 LAST $XR0 29 
J 0
(-6911 5375);
DISPLAY 0.638298 (-6911 5375);
PAINT MONO (-6911 5375);
FORCEPROP 2 LAST CDS_LIB standard
J 0
(-7100 5375);
DISPLAY INVISIBLE (-7100 5375);
FORCEPROP 1 LAST OFFPAGE TRUE
J 0
(-6775 5250);
DISPLAY 0.872340 (-6775 5250);
PAINT GREEN (-6775 5250);
DISPLAY INVISIBLE (-6775 5250);
FORCEPROP 1 LAST COMMENT_BODY TRUE
J 0
(-7145 5280);
DISPLAY 0.872340 (-7145 5280);
PAINT PEACH (-7145 5280);
DISPLAY INVISIBLE (-7145 5280);
FORCEPROP 2 LAST PATH I128
J 0
(-6925 5450);
DISPLAY 0.680851 (-6925 5450);
DISPLAY INVISIBLE (-6925 5450);
FORCEADD OFFPAGE..2
(-7100 5325);
FORCEPROP 2 LAST $XR1 76 
J 0
(-6821 5325);
DISPLAY 0.638298 (-6821 5325);
PAINT MONO (-6821 5325);
FORCEPROP 2 LAST $XR0 29 
J 0
(-6911 5325);
DISPLAY 0.638298 (-6911 5325);
PAINT MONO (-6911 5325);
FORCEPROP 2 LAST CDS_LIB standard
J 0
(-7100 5325);
DISPLAY INVISIBLE (-7100 5325);
FORCEPROP 1 LAST OFFPAGE TRUE
J 0
(-6775 5200);
DISPLAY 0.872340 (-6775 5200);
PAINT GREEN (-6775 5200);
DISPLAY INVISIBLE (-6775 5200);
FORCEPROP 1 LAST COMMENT_BODY TRUE
J 0
(-7145 5230);
DISPLAY 0.872340 (-7145 5230);
PAINT PEACH (-7145 5230);
DISPLAY INVISIBLE (-7145 5230);
FORCEPROP 2 LAST PATH I129
J 0
(-6925 5400);
DISPLAY 0.680851 (-6925 5400);
DISPLAY INVISIBLE (-6925 5400);
FORCEADD OFFPAGE..2
(-7100 5275);
FORCEPROP 2 LAST $XR1 76 
J 0
(-6821 5275);
DISPLAY 0.638298 (-6821 5275);
PAINT MONO (-6821 5275);
FORCEPROP 2 LAST $XR0 29 
J 0
(-6911 5275);
DISPLAY 0.638298 (-6911 5275);
PAINT MONO (-6911 5275);
FORCEPROP 2 LAST CDS_LIB standard
J 0
(-7100 5275);
DISPLAY INVISIBLE (-7100 5275);
FORCEPROP 2 LAST PATH I130
J 0
(-6925 5350);
DISPLAY 0.680851 (-6925 5350);
DISPLAY INVISIBLE (-6925 5350);
FORCEPROP 1 LAST COMMENT_BODY TRUE
J 0
(-7145 5180);
DISPLAY 0.872340 (-7145 5180);
PAINT PEACH (-7145 5180);
DISPLAY INVISIBLE (-7145 5180);
FORCEPROP 1 LAST OFFPAGE TRUE
J 0
(-6775 5150);
DISPLAY 0.872340 (-6775 5150);
PAINT GREEN (-6775 5150);
DISPLAY INVISIBLE (-6775 5150);
FORCEADD Q_RES..2
(-8550 5875);
FORCEPROP 1 LAST LOCATION R1532
J 0
(-8525 5750);
DISPLAY 0.489362 (-8525 5750);
PAINT SKYBLUE (-8525 5750);
FORCEPROP 0 LAST $SEC 1
J 0
(-8500 5975);
DISPLAY 0.680851 (-8500 5975);
PAINT MONO (-8500 5975);
DISPLAY INVISIBLE (-8500 5975);
FORCEPROP 0 LAST CDS_SEC 1
J 0
(-8500 5975);
DISPLAY 0.680851 (-8500 5975);
DISPLAY INVISIBLE (-8500 5975);
FORCEPROP 1 LASTPIN (-8550 5975) $PN 1
J 0
(-8545 5937);
DISPLAY 0.489362 (-8545 5937);
PAINT MONO (-8545 5937);
FORCEPROP 1 LASTPIN (-8550 5775) $PN 2
J 0
(-8545 5785);
DISPLAY 0.489362 (-8545 5785);
PAINT MONO (-8545 5785);
FORCEPROP 1 LAST TOLERANCE 5%
J 0
(-8505 5900);
DISPLAY 0.489362 (-8505 5900);
PAINT SKYBLUE (-8505 5900);
FORCEPROP 1 LAST WATTAGE 1/16W
J 0
(-8510 5850);
DISPLAY 0.489362 (-8510 5850);
PAINT SKYBLUE (-8510 5850);
FORCEPROP 1 LAST VALUE 1K
J 0
(-8505 5950);
DISPLAY 0.489362 (-8505 5950);
PAINT SKYBLUE (-8505 5950);
FORCEPROP 1 LAST MATERIAL EMPTY
J 0
(-8510 5800);
DISPLAY 0.489362 (-8510 5800);
PAINT RED (-8510 5800);
FORCEPROP 2 LAST CDS_LIB pure_quanta
J 0
(-8550 5875);
DISPLAY INVISIBLE (-8550 5875);
FORCEPROP 1 LAST PATH I131
J 0
(-8500 6050);
DISPLAY 0.978723 (-8500 6050);
PAINT WHITE (-8500 6050);
DISPLAY INVISIBLE (-8500 6050);
FORCEPROP 1 LAST PART_NUMBER TMP_QCS21002JB34
J 0
(-8510 5750);
DISPLAY 0.489362 (-8510 5750);
PAINT SKYBLUE (-8510 5750);
DISPLAY INVISIBLE (-8510 5750);
FORCEPROP 1 LAST PACK_TYPE 0402LF
J 0
(-8500 5750);
DISPLAY 0.382979 (-8500 5750);
PAINT SKYBLUE (-8500 5750);
DISPLAY INVISIBLE (-8500 5750);
FORCEADD Q_RES..2
(-8725 5875);
FORCEPROP 1 LAST LOCATION R1531
J 0
(-8675 5750);
DISPLAY 0.489362 (-8675 5750);
PAINT SKYBLUE (-8675 5750);
FORCEPROP 0 LAST $SEC 1
J 0
(-8675 5975);
DISPLAY 0.680851 (-8675 5975);
PAINT MONO (-8675 5975);
DISPLAY INVISIBLE (-8675 5975);
FORCEPROP 0 LAST CDS_SEC 1
J 0
(-8675 5975);
DISPLAY 0.680851 (-8675 5975);
DISPLAY INVISIBLE (-8675 5975);
FORCEPROP 1 LASTPIN (-8725 5975) $PN 1
J 0
(-8720 5937);
DISPLAY 0.489362 (-8720 5937);
PAINT MONO (-8720 5937);
FORCEPROP 1 LASTPIN (-8725 5775) $PN 2
J 0
(-8720 5785);
DISPLAY 0.489362 (-8720 5785);
PAINT MONO (-8720 5785);
FORCEPROP 1 LAST WATTAGE 1/16W
J 0
(-8685 5850);
DISPLAY 0.489362 (-8685 5850);
PAINT SKYBLUE (-8685 5850);
FORCEPROP 1 LAST TOLERANCE 5%
J 0
(-8680 5900);
DISPLAY 0.489362 (-8680 5900);
PAINT SKYBLUE (-8680 5900);
FORCEPROP 1 LAST MATERIAL EMPTY
J 0
(-8685 5800);
DISPLAY 0.489362 (-8685 5800);
PAINT RED (-8685 5800);
FORCEPROP 1 LAST VALUE 1K
J 0
(-8680 5950);
DISPLAY 0.489362 (-8680 5950);
PAINT SKYBLUE (-8680 5950);
FORCEPROP 2 LAST CDS_LIB pure_quanta
J 0
(-8725 5875);
DISPLAY INVISIBLE (-8725 5875);
FORCEPROP 1 LAST PATH I132
J 0
(-8675 6050);
DISPLAY 0.978723 (-8675 6050);
PAINT WHITE (-8675 6050);
DISPLAY INVISIBLE (-8675 6050);
FORCEPROP 1 LAST PART_NUMBER TMP_QCS21002JB34
J 0
(-8685 5750);
DISPLAY 0.489362 (-8685 5750);
PAINT SKYBLUE (-8685 5750);
DISPLAY INVISIBLE (-8685 5750);
FORCEPROP 1 LAST PACK_TYPE 0402LF
J 0
(-8675 5750);
DISPLAY 0.382979 (-8675 5750);
PAINT SKYBLUE (-8675 5750);
DISPLAY INVISIBLE (-8675 5750);
FORCEADD Q_RES..2
(-8900 5875);
FORCEPROP 1 LAST LOCATION R1530
J 0
(-8875 5750);
DISPLAY 0.489362 (-8875 5750);
PAINT SKYBLUE (-8875 5750);
FORCEPROP 0 LAST $SEC 1
J 0
(-8850 5975);
DISPLAY 0.680851 (-8850 5975);
PAINT MONO (-8850 5975);
DISPLAY INVISIBLE (-8850 5975);
FORCEPROP 0 LAST CDS_SEC 1
J 0
(-8850 5975);
DISPLAY 0.680851 (-8850 5975);
DISPLAY INVISIBLE (-8850 5975);
FORCEPROP 1 LASTPIN (-8900 5975) $PN 1
J 0
(-8895 5937);
DISPLAY 0.489362 (-8895 5937);
PAINT MONO (-8895 5937);
FORCEPROP 1 LASTPIN (-8900 5775) $PN 2
J 0
(-8895 5785);
DISPLAY 0.489362 (-8895 5785);
PAINT MONO (-8895 5785);
FORCEPROP 1 LAST VALUE 1K
J 0
(-8855 5950);
DISPLAY 0.489362 (-8855 5950);
PAINT SKYBLUE (-8855 5950);
FORCEPROP 1 LAST TOLERANCE 5%
J 0
(-8855 5900);
DISPLAY 0.489362 (-8855 5900);
PAINT SKYBLUE (-8855 5900);
FORCEPROP 1 LAST WATTAGE 1/16W
J 0
(-8860 5850);
DISPLAY 0.489362 (-8860 5850);
PAINT SKYBLUE (-8860 5850);
FORCEPROP 1 LAST MATERIAL EMPTY
J 0
(-8860 5800);
DISPLAY 0.489362 (-8860 5800);
PAINT RED (-8860 5800);
FORCEPROP 2 LAST CDS_LIB pure_quanta
J 0
(-8900 5875);
DISPLAY INVISIBLE (-8900 5875);
FORCEPROP 1 LAST PATH I133
J 0
(-8850 6050);
DISPLAY 0.978723 (-8850 6050);
PAINT WHITE (-8850 6050);
DISPLAY INVISIBLE (-8850 6050);
FORCEPROP 1 LAST PART_NUMBER TMP_QCS21002JB34
J 0
(-8860 5750);
DISPLAY 0.489362 (-8860 5750);
PAINT SKYBLUE (-8860 5750);
DISPLAY INVISIBLE (-8860 5750);
FORCEPROP 1 LAST PACK_TYPE 0402LF
J 0
(-8850 5750);
DISPLAY 0.382979 (-8850 5750);
PAINT SKYBLUE (-8850 5750);
DISPLAY INVISIBLE (-8850 5750);
FORCEADD Q_RES..2
(-9075 5875);
FORCEPROP 1 LAST LOCATION R1529
J 0
(-9050 5750);
DISPLAY 0.489362 (-9050 5750);
PAINT SKYBLUE (-9050 5750);
FORCEPROP 0 LAST $SEC 1
J 0
(-9025 5975);
DISPLAY 0.680851 (-9025 5975);
PAINT MONO (-9025 5975);
DISPLAY INVISIBLE (-9025 5975);
FORCEPROP 0 LAST CDS_SEC 1
J 0
(-9025 5975);
DISPLAY 0.680851 (-9025 5975);
DISPLAY INVISIBLE (-9025 5975);
FORCEPROP 1 LASTPIN (-9075 5975) $PN 1
J 0
(-9070 5937);
DISPLAY 0.489362 (-9070 5937);
PAINT MONO (-9070 5937);
FORCEPROP 1 LASTPIN (-9075 5775) $PN 2
J 0
(-9070 5785);
DISPLAY 0.489362 (-9070 5785);
PAINT MONO (-9070 5785);
FORCEPROP 1 LAST WATTAGE 1/16W
J 0
(-9035 5850);
DISPLAY 0.489362 (-9035 5850);
PAINT SKYBLUE (-9035 5850);
FORCEPROP 1 LAST MATERIAL EMPTY
J 0
(-9035 5800);
DISPLAY 0.489362 (-9035 5800);
PAINT RED (-9035 5800);
FORCEPROP 1 LAST VALUE 1K
J 0
(-9030 5950);
DISPLAY 0.489362 (-9030 5950);
PAINT SKYBLUE (-9030 5950);
FORCEPROP 1 LAST TOLERANCE 5%
J 0
(-9030 5900);
DISPLAY 0.489362 (-9030 5900);
PAINT SKYBLUE (-9030 5900);
FORCEPROP 2 LAST CDS_LIB pure_quanta
J 0
(-9075 5875);
DISPLAY INVISIBLE (-9075 5875);
FORCEPROP 1 LAST PATH I134
J 0
(-9025 6050);
DISPLAY 0.978723 (-9025 6050);
PAINT WHITE (-9025 6050);
DISPLAY INVISIBLE (-9025 6050);
FORCEPROP 1 LAST PART_NUMBER TMP_QCS21002JB34
J 0
(-9035 5750);
DISPLAY 0.489362 (-9035 5750);
PAINT SKYBLUE (-9035 5750);
DISPLAY INVISIBLE (-9035 5750);
FORCEPROP 1 LAST PACK_TYPE 0402LF
J 0
(-9025 5750);
DISPLAY 0.382979 (-9025 5750);
PAINT SKYBLUE (-9025 5750);
DISPLAY INVISIBLE (-9025 5750);
FORCEADD OFFPAGE..1
(-6925 2125);
FORCEPROP 2 LAST $XR1 80 
J 0
(-7266 2125);
DISPLAY 0.638298 (-7266 2125);
PAINT MONO (-7266 2125);
FORCEPROP 2 LAST $XR0 76 
J 0
(-7176 2125);
DISPLAY 0.638298 (-7176 2125);
PAINT MONO (-7176 2125);
FORCEPROP 1 LAST OFFPAGE TRUE
J 0
(-6595 1995);
PAINT GREEN (-6595 1995);
DISPLAY INVISIBLE (-6595 1995);
FORCEPROP 1 LAST COMMENT_BODY TRUE
J 0
(-6795 2025);
DISPLAY 1.106383 (-6795 2025);
PAINT PEACH (-6795 2025);
DISPLAY INVISIBLE (-6795 2025);
FORCEPROP 2 LAST PATH I136
J 0
(-7125 2175);
DISPLAY 0.680851 (-7125 2175);
DISPLAY INVISIBLE (-7125 2175);
FORCEPROP 2 LAST CDS_LIB standard
J 0
(-6925 2125);
DISPLAY INVISIBLE (-6925 2125);
FORCEADD UNIVERSAL_GND..1
(-6200 2500);
FORCEPROP 3 LASTPIN (-6200 2550) SIG_NAME GND\g
J 0
(-6190 2560);
DISPLAY 0.659574 (-6190 2560);
PAINT MONO (-6190 2560);
DISPLAY INVISIBLE (-6190 2560);
FORCEPROP 2 LAST CDS_LIB pure_quanta_power
J 0
(-6200 2500);
DISPLAY INVISIBLE (-6200 2500);
FORCEPROP 1 LAST PATH I138
J 0
(-6125 2500);
DISPLAY 0.872340 (-6125 2500);
PAINT AQUA (-6125 2500);
DISPLAY INVISIBLE (-6125 2500);
FORCEPROP 1 LAST HDL_POWER GND
J 1
(-6175 2425);
DISPLAY 0.872340 (-6175 2425);
PAINT GREEN (-6175 2425);
DISPLAY INVISIBLE (-6175 2425);
FORCEADD UNIVERSAL_GND..1
R 2
(-4725 2450);
FORCEPROP 3 LASTPIN (-4725 2500) SIG_NAME GND\g
J 0
(-4715 2510);
DISPLAY 0.659574 (-4715 2510);
PAINT MONO (-4715 2510);
DISPLAY INVISIBLE (-4715 2510);
FORCEPROP 2 LAST CDS_LIB pure_quanta_power
J 0
(-4725 2450);
DISPLAY INVISIBLE (-4725 2450);
FORCEPROP 1 LAST PATH I139
J 2
(-4800 2450);
DISPLAY 0.872340 (-4800 2450);
PAINT AQUA (-4800 2450);
DISPLAY INVISIBLE (-4800 2450);
FORCEPROP 1 LAST HDL_POWER GND
J 1
(-4750 2375);
DISPLAY 0.872340 (-4750 2375);
PAINT GREEN (-4750 2375);
DISPLAY INVISIBLE (-4750 2375);
FORCEADD Q_RES..2
(-1175 5625);
FORCEPROP 1 LAST $LOCATION R1547
J 0
(-1150 5725);
DISPLAY 0.510638 (-1150 5725);
PAINT SKYBLUE (-1150 5725);
FORCEPROP 0 LAST CDS_LOCATION R1547
J 0
(-1150 5750);
DISPLAY 0.680851 (-1150 5750);
DISPLAY INVISIBLE (-1150 5750);
FORCEPROP 0 LAST $SEC 1
J 0
(-1150 5750);
DISPLAY 0.680851 (-1150 5750);
PAINT MONO (-1150 5750);
DISPLAY INVISIBLE (-1150 5750);
FORCEPROP 0 LAST CDS_SEC 1
J 0
(-1150 5750);
DISPLAY 0.680851 (-1150 5750);
DISPLAY INVISIBLE (-1150 5750);
FORCEPROP 1 LASTPIN (-1175 5725) $PN 1
J 0
(-1170 5687);
DISPLAY 0.787234 (-1170 5687);
PAINT MONO (-1170 5687);
FORCEPROP 1 LASTPIN (-1175 5525) $PN 2
J 0
(-1170 5535);
DISPLAY 0.787234 (-1170 5535);
PAINT MONO (-1170 5535);
FORCEPROP 1 LAST VALUE 4.7K
J 0
(-1150 5675);
DISPLAY 0.510638 (-1150 5675);
PAINT SKYBLUE (-1150 5675);
FORCEPROP 1 LAST TOLERANCE 5%
J 0
(-1150 5625);
DISPLAY 0.510638 (-1150 5625);
PAINT SKYBLUE (-1150 5625);
FORCEPROP 1 LAST MATERIAL CHIP
J 0
(-1150 5575);
DISPLAY 0.510638 (-1150 5575);
PAINT SKYBLUE (-1150 5575);
FORCEPROP 2 LAST CDS_LIB pure_quanta
J 0
(-1175 5625);
DISPLAY INVISIBLE (-1175 5625);
FORCEPROP 1 LAST PATH I148
J 0
(-1125 5800);
DISPLAY 0.978723 (-1125 5800);
PAINT WHITE (-1125 5800);
DISPLAY INVISIBLE (-1125 5800);
FORCEPROP 1 LAST WATTAGE 1/16W
J 0
(-1135 5600);
DISPLAY 0.978723 (-1135 5600);
DISPLAY INVISIBLE (-1135 5600);
FORCEPROP 1 LAST PART_NUMBER TMP_QCS24702JB38
J 0
(-1135 5500);
DISPLAY 0.978723 (-1135 5500);
DISPLAY INVISIBLE (-1135 5500);
FORCEPROP 1 LAST PACK_TYPE 0402LF
J 0
(-1135 5450);
DISPLAY 0.978723 (-1135 5450);
DISPLAY INVISIBLE (-1135 5450);
FORCEADD OFFPAGE..2
R 2
(-3125 5150);
FORCEPROP 2 LAST $XR1 117 
J 0
(-3499 5150);
DISPLAY 0.638298 (-3499 5150);
PAINT MONO (-3499 5150);
FORCEPROP 2 LAST $XR0 76 
J 0
(-3379 5150);
DISPLAY 0.638298 (-3379 5150);
PAINT MONO (-3379 5150);
FORCEPROP 2 LAST CDS_LIB standard
J 0
(-3125 5150);
DISPLAY INVISIBLE (-3125 5150);
FORCEPROP 2 LAST PATH I149
J 0
(-3075 5225);
DISPLAY 0.680851 (-3075 5225);
DISPLAY INVISIBLE (-3075 5225);
FORCEPROP 1 LAST COMMENT_BODY TRUE
J 2
(-3080 5055);
DISPLAY 0.872340 (-3080 5055);
PAINT PEACH (-3080 5055);
DISPLAY INVISIBLE (-3080 5055);
FORCEPROP 1 LAST OFFPAGE TRUE
J 2
(-3450 5025);
DISPLAY 0.872340 (-3450 5025);
PAINT GREEN (-3450 5025);
DISPLAY INVISIBLE (-3450 5025);
FORCEADD Q_RES..2
(-9250 5875);
FORCEPROP 1 LAST $LOCATION R1567
J 0
(-9225 5750);
DISPLAY 0.638298 (-9225 5750);
PAINT SKYBLUE (-9225 5750);
FORCEPROP 0 LAST CDS_LOCATION R1567
J 0
(-9225 5975);
DISPLAY 0.680851 (-9225 5975);
DISPLAY INVISIBLE (-9225 5975);
FORCEPROP 0 LAST $SEC 1
J 0
(-9225 5975);
DISPLAY 0.680851 (-9225 5975);
PAINT MONO (-9225 5975);
DISPLAY INVISIBLE (-9225 5975);
FORCEPROP 0 LAST CDS_SEC 1
J 0
(-9225 5975);
DISPLAY 0.680851 (-9225 5975);
DISPLAY INVISIBLE (-9225 5975);
FORCEPROP 1 LASTPIN (-9250 5975) $PN 1
J 0
(-9245 5937);
DISPLAY 0.787234 (-9245 5937);
PAINT MONO (-9245 5937);
FORCEPROP 1 LASTPIN (-9250 5775) $PN 2
J 0
(-9245 5785);
DISPLAY 0.787234 (-9245 5785);
PAINT MONO (-9245 5785);
FORCEPROP 1 LAST VALUE 4.7K
J 0
(-9225 5950);
DISPLAY 0.404255 (-9225 5950);
PAINT SKYBLUE (-9225 5950);
FORCEPROP 1 LAST TOLERANCE 5%
J 0
(-9225 5900);
DISPLAY 0.404255 (-9225 5900);
PAINT SKYBLUE (-9225 5900);
FORCEPROP 1 LAST WATTAGE 1/16W
J 0
(-9225 5850);
DISPLAY 0.404255 (-9225 5850);
PAINT SKYBLUE (-9225 5850);
FORCEPROP 1 LAST MATERIAL CHIP
J 0
(-9225 5800);
DISPLAY 0.510638 (-9225 5800);
PAINT SKYBLUE (-9225 5800);
FORCEPROP 1 LAST PART_NUMBER TMP_QCS24702JB38
J 0
(-9210 5750);
DISPLAY 0.978723 (-9210 5750);
DISPLAY INVISIBLE (-9210 5750);
FORCEPROP 1 LAST PACK_TYPE 0402LF
J 0
(-9210 5700);
DISPLAY 0.978723 (-9210 5700);
DISPLAY INVISIBLE (-9210 5700);
FORCEPROP 1 LAST PATH I150
J 0
(-9200 6050);
DISPLAY 0.978723 (-9200 6050);
PAINT WHITE (-9200 6050);
DISPLAY INVISIBLE (-9200 6050);
FORCEPROP 2 LAST CDS_LIB pure_quanta
J 0
(-9250 5875);
DISPLAY INVISIBLE (-9250 5875);
FORCEADD OFFPAGE..2
(-7100 5225);
FORCEPROP 2 LAST $XR1 76 
J 0
(-6821 5225);
DISPLAY 0.638298 (-6821 5225);
PAINT MONO (-6821 5225);
FORCEPROP 2 LAST $XR0 80 
J 0
(-6911 5225);
DISPLAY 0.638298 (-6911 5225);
PAINT MONO (-6911 5225);
FORCEPROP 1 LAST OFFPAGE TRUE
J 0
(-6775 5100);
DISPLAY 0.872340 (-6775 5100);
PAINT GREEN (-6775 5100);
DISPLAY INVISIBLE (-6775 5100);
FORCEPROP 1 LAST COMMENT_BODY TRUE
J 0
(-7145 5130);
DISPLAY 0.872340 (-7145 5130);
PAINT PEACH (-7145 5130);
DISPLAY INVISIBLE (-7145 5130);
FORCEPROP 2 LAST PATH I151
J 0
(-6925 5300);
DISPLAY 0.680851 (-6925 5300);
DISPLAY INVISIBLE (-6925 5300);
FORCEPROP 2 LAST CDS_LIB standard
J 0
(-7100 5225);
DISPLAY INVISIBLE (-7100 5225);
FORCEADD OFFPAGE..1
(-6800 4225);
FORCEPROP 2 LAST $XR1 76 
J 0
(-7141 4225);
DISPLAY 0.638298 (-7141 4225);
PAINT MONO (-7141 4225);
FORCEPROP 2 LAST $XR0 29 
J 0
(-7051 4225);
DISPLAY 0.638298 (-7051 4225);
PAINT MONO (-7051 4225);
FORCEPROP 2 LAST PATH I176
J 0
(-7050 4275);
DISPLAY 0.680851 (-7050 4275);
DISPLAY INVISIBLE (-7050 4275);
FORCEPROP 1 LAST COMMENT_BODY TRUE
J 0
(-6670 4125);
DISPLAY 1.106383 (-6670 4125);
PAINT PEACH (-6670 4125);
DISPLAY INVISIBLE (-6670 4125);
FORCEPROP 1 LAST OFFPAGE TRUE
J 0
(-6470 4095);
PAINT GREEN (-6470 4095);
DISPLAY INVISIBLE (-6470 4095);
FORCEPROP 2 LAST CDS_LIB standard
J 0
(-6800 4225);
DISPLAY INVISIBLE (-6800 4225);
FORCEADD OFFPAGE..2
(-3000 4175);
FORCEPROP 2 LAST $XR1 117 
J 0
(-2721 4175);
DISPLAY 0.638298 (-2721 4175);
PAINT MONO (-2721 4175);
FORCEPROP 2 LAST $XR0 76 
J 0
(-2811 4175);
DISPLAY 0.638298 (-2811 4175);
PAINT MONO (-2811 4175);
FORCEPROP 2 LAST PATH I177
J 0
(-2700 4225);
DISPLAY 0.680851 (-2700 4225);
DISPLAY INVISIBLE (-2700 4225);
FORCEPROP 1 LAST COMMENT_BODY TRUE
J 0
(-3045 4080);
DISPLAY 0.872340 (-3045 4080);
PAINT PEACH (-3045 4080);
DISPLAY INVISIBLE (-3045 4080);
FORCEPROP 1 LAST OFFPAGE TRUE
J 0
(-2675 4050);
DISPLAY 0.872340 (-2675 4050);
PAINT GREEN (-2675 4050);
DISPLAY INVISIBLE (-2675 4050);
FORCEPROP 2 LAST CDS_LIB standard
J 0
(-3000 4175);
DISPLAY INVISIBLE (-3000 4175);
FORCEADD Q_RES..1
(-3950 4175);
FORCEPROP 1 LAST LOCATION R608
J 0
(-3850 4175);
DISPLAY 0.489362 (-3850 4175);
PAINT SKYBLUE (-3850 4175);
FORCEPROP 0 LAST $SEC 1
J 0
(-3850 4200);
DISPLAY 0.680851 (-3850 4200);
PAINT MONO (-3850 4200);
DISPLAY INVISIBLE (-3850 4200);
FORCEPROP 0 LAST CDS_SEC 1
J 0
(-3850 4200);
DISPLAY 1.021277 (-3850 4200);
DISPLAY INVISIBLE (-3850 4200);
FORCEPROP 1 LASTPIN (-4050 4175) $PN 1
J 0
(-4038 4187);
DISPLAY 0.489362 (-4038 4187);
PAINT MONO (-4038 4187);
FORCEPROP 1 LASTPIN (-3850 4175) $PN 2
J 0
(-3888 4187);
DISPLAY 0.489362 (-3888 4187);
PAINT MONO (-3888 4187);
FORCEPROP 1 LAST VALUE 0
J 2
(-4050 4175);
DISPLAY 0.489362 (-4050 4175);
PAINT SKYBLUE (-4050 4175);
FORCEPROP 1 LAST PATH I178
J 0
(-4000 4325);
DISPLAY 0.978723 (-4000 4325);
PAINT WHITE (-4000 4325);
DISPLAY INVISIBLE (-4000 4325);
FORCEPROP 1 LAST PACK_TYPE 0402LF
J 0
(-3900 4100);
DISPLAY 0.489362 (-3900 4100);
PAINT SKYBLUE (-3900 4100);
DISPLAY INVISIBLE (-3900 4100);
FORCEPROP 1 LAST PART_NUMBER CS00002JB38
J 0
(-3925 4225);
DISPLAY 0.489362 (-3925 4225);
PAINT SKYBLUE (-3925 4225);
DISPLAY INVISIBLE (-3925 4225);
FORCEPROP 1 LAST TOLERANCE 5%
J 0
(-3975 4100);
DISPLAY 0.489362 (-3975 4100);
PAINT SKYBLUE (-3975 4100);
DISPLAY INVISIBLE (-3975 4100);
FORCEPROP 1 LAST MATERIAL CHIP
J 0
(-3525 4100);
DISPLAY 0.489362 (-3525 4100);
PAINT SKYBLUE (-3525 4100);
DISPLAY INVISIBLE (-3525 4100);
FORCEPROP 1 LAST WATTAGE 1/16W
J 2
(-3550 4100);
DISPLAY 0.489362 (-3550 4100);
PAINT SKYBLUE (-3550 4100);
DISPLAY INVISIBLE (-3550 4100);
FORCEPROP 2 LAST CDS_LIB pure_quanta
J 0
(-3950 4175);
DISPLAY INVISIBLE (-3950 4175);
FORCEADD OFFPAGE..2
(-3000 4225);
FORCEPROP 2 LAST $XR1 117 
J 0
(-2721 4225);
DISPLAY 0.638298 (-2721 4225);
PAINT MONO (-2721 4225);
FORCEPROP 2 LAST $XR0 76 
J 0
(-2811 4225);
DISPLAY 0.638298 (-2811 4225);
PAINT MONO (-2811 4225);
FORCEPROP 2 LAST PATH I179
J 0
(-2800 4275);
DISPLAY 0.680851 (-2800 4275);
DISPLAY INVISIBLE (-2800 4275);
FORCEPROP 1 LAST COMMENT_BODY TRUE
J 0
(-3045 4130);
DISPLAY 0.872340 (-3045 4130);
PAINT PEACH (-3045 4130);
DISPLAY INVISIBLE (-3045 4130);
FORCEPROP 1 LAST OFFPAGE TRUE
J 0
(-2675 4100);
DISPLAY 0.872340 (-2675 4100);
PAINT GREEN (-2675 4100);
DISPLAY INVISIBLE (-2675 4100);
FORCEPROP 2 LAST CDS_LIB standard
J 0
(-3000 4225);
DISPLAY INVISIBLE (-3000 4225);
FORCEADD Q_RES..1
(-3950 4225);
FORCEPROP 1 LAST LOCATION R600
J 0
(-3850 4225);
DISPLAY 0.489362 (-3850 4225);
PAINT SKYBLUE (-3850 4225);
FORCEPROP 0 LAST $SEC 1
J 0
(-3850 4250);
DISPLAY 0.680851 (-3850 4250);
PAINT MONO (-3850 4250);
DISPLAY INVISIBLE (-3850 4250);
FORCEPROP 0 LAST CDS_SEC 1
J 0
(-3850 4250);
DISPLAY 1.021277 (-3850 4250);
DISPLAY INVISIBLE (-3850 4250);
FORCEPROP 1 LASTPIN (-4050 4225) $PN 1
J 0
(-4038 4237);
DISPLAY 0.489362 (-4038 4237);
PAINT MONO (-4038 4237);
FORCEPROP 1 LASTPIN (-3850 4225) $PN 2
J 0
(-3888 4237);
DISPLAY 0.489362 (-3888 4237);
PAINT MONO (-3888 4237);
FORCEPROP 1 LAST VALUE 0
J 2
(-4050 4225);
DISPLAY 0.489362 (-4050 4225);
PAINT SKYBLUE (-4050 4225);
FORCEPROP 1 LAST PATH I180
J 0
(-4000 4375);
DISPLAY 0.978723 (-4000 4375);
PAINT WHITE (-4000 4375);
DISPLAY INVISIBLE (-4000 4375);
FORCEPROP 1 LAST PACK_TYPE 0402LF
J 0
(-3900 4150);
DISPLAY 0.489362 (-3900 4150);
PAINT SKYBLUE (-3900 4150);
DISPLAY INVISIBLE (-3900 4150);
FORCEPROP 1 LAST PART_NUMBER CS00002JB38
J 0
(-3925 4275);
DISPLAY 0.489362 (-3925 4275);
PAINT SKYBLUE (-3925 4275);
DISPLAY INVISIBLE (-3925 4275);
FORCEPROP 1 LAST TOLERANCE 5%
J 0
(-3975 4150);
DISPLAY 0.489362 (-3975 4150);
PAINT SKYBLUE (-3975 4150);
DISPLAY INVISIBLE (-3975 4150);
FORCEPROP 1 LAST MATERIAL CHIP
J 0
(-3525 4150);
DISPLAY 0.489362 (-3525 4150);
PAINT SKYBLUE (-3525 4150);
DISPLAY INVISIBLE (-3525 4150);
FORCEPROP 1 LAST WATTAGE 1/16W
J 2
(-3550 4150);
DISPLAY 0.489362 (-3550 4150);
PAINT SKYBLUE (-3550 4150);
DISPLAY INVISIBLE (-3550 4150);
FORCEPROP 2 LAST CDS_LIB pure_quanta
J 0
(-3950 4225);
DISPLAY INVISIBLE (-3950 4225);
FORCEADD OFFPAGE..1
(-6800 4175);
FORCEPROP 2 LAST $XR1 76 
J 0
(-7141 4175);
DISPLAY 0.638298 (-7141 4175);
PAINT MONO (-7141 4175);
FORCEPROP 2 LAST $XR0 29 
J 0
(-7051 4175);
DISPLAY 0.638298 (-7051 4175);
PAINT MONO (-7051 4175);
FORCEPROP 2 LAST PATH I181
J 0
(-7075 4225);
DISPLAY 0.680851 (-7075 4225);
DISPLAY INVISIBLE (-7075 4225);
FORCEPROP 1 LAST COMMENT_BODY TRUE
J 0
(-6670 4075);
DISPLAY 1.106383 (-6670 4075);
PAINT PEACH (-6670 4075);
DISPLAY INVISIBLE (-6670 4075);
FORCEPROP 1 LAST OFFPAGE TRUE
J 0
(-6470 4045);
PAINT GREEN (-6470 4045);
DISPLAY INVISIBLE (-6470 4045);
FORCEPROP 2 LAST CDS_LIB standard
J 0
(-6800 4175);
DISPLAY INVISIBLE (-6800 4175);
FORCEADD OFFPAGE..1
(-6800 3825);
FORCEPROP 2 LAST $XR0 80 
J 0
(-7051 3825);
DISPLAY 0.638298 (-7051 3825);
PAINT MONO (-7051 3825);
FORCEPROP 1 LAST OFFPAGE TRUE
J 0
(-6470 3695);
PAINT GREEN (-6470 3695);
DISPLAY INVISIBLE (-6470 3695);
FORCEPROP 1 LAST COMMENT_BODY TRUE
J 0
(-6670 3725);
DISPLAY 1.106383 (-6670 3725);
PAINT PEACH (-6670 3725);
DISPLAY INVISIBLE (-6670 3725);
FORCEPROP 2 LAST PATH I189
J 0
(-6750 3900);
DISPLAY 0.680851 (-6750 3900);
DISPLAY INVISIBLE (-6750 3900);
FORCEPROP 2 LAST CDS_LIB standard
J 0
(-6800 3825);
DISPLAY INVISIBLE (-6800 3825);
FORCEADD OFFPAGE..2
R 2
(-3125 5100);
FORCEPROP 2 LAST $XR1 117 
J 0
(-3499 5100);
DISPLAY 0.638298 (-3499 5100);
PAINT MONO (-3499 5100);
FORCEPROP 2 LAST $XR0 76 
J 0
(-3379 5100);
DISPLAY 0.638298 (-3379 5100);
PAINT MONO (-3379 5100);
FORCEPROP 1 LAST OFFPAGE TRUE
J 2
(-3450 4975);
DISPLAY 0.872340 (-3450 4975);
PAINT GREEN (-3450 4975);
DISPLAY INVISIBLE (-3450 4975);
FORCEPROP 1 LAST COMMENT_BODY TRUE
J 2
(-3080 5005);
DISPLAY 0.872340 (-3080 5005);
PAINT PEACH (-3080 5005);
DISPLAY INVISIBLE (-3080 5005);
FORCEPROP 2 LAST PATH I190
J 0
(-3075 5175);
DISPLAY 0.680851 (-3075 5175);
DISPLAY INVISIBLE (-3075 5175);
FORCEPROP 2 LAST CDS_LIB standard
J 0
(-3125 5100);
DISPLAY INVISIBLE (-3125 5100);
FORCEADD Q_RES..2
R 2
(-1025 5625);
FORCEPROP 1 LAST $LOCATION R1655
J 0
(-1000 5725);
DISPLAY 0.489362 (-1000 5725);
PAINT SKYBLUE (-1000 5725);
FORCEPROP 0 LAST CDS_LOCATION R1655
J 0
(-1000 5750);
DISPLAY 0.680851 (-1000 5750);
DISPLAY INVISIBLE (-1000 5750);
FORCEPROP 0 LAST $SEC 1
J 0
(-1000 5750);
DISPLAY 0.680851 (-1000 5750);
PAINT MONO (-1000 5750);
DISPLAY INVISIBLE (-1000 5750);
FORCEPROP 0 LAST CDS_SEC 1
J 0
(-1000 5750);
DISPLAY 0.680851 (-1000 5750);
DISPLAY INVISIBLE (-1000 5750);
FORCEPROP 1 LASTPIN (-1025 5725) $PN 1
J 2
(-1030 5687);
DISPLAY 0.787234 (-1030 5687);
PAINT MONO (-1030 5687);
FORCEPROP 1 LASTPIN (-1025 5525) $PN 2
J 2
(-1030 5535);
DISPLAY 0.787234 (-1030 5535);
PAINT MONO (-1030 5535);
FORCEPROP 1 LAST VALUE 1K
J 0
(-1000 5675);
DISPLAY 0.489362 (-1000 5675);
PAINT SKYBLUE (-1000 5675);
FORCEPROP 1 LAST TOLERANCE 5%
J 0
(-1000 5625);
DISPLAY 0.489362 (-1000 5625);
PAINT SKYBLUE (-1000 5625);
FORCEPROP 1 LAST MATERIAL EMPTY
J 0
(-1000 5575);
DISPLAY 0.489362 (-1000 5575);
PAINT RED (-1000 5575);
FORCEPROP 1 LAST PACK_TYPE 0402LF
J 2
(-1075 5575);
DISPLAY 0.489362 (-1075 5575);
PAINT SKYBLUE (-1075 5575);
DISPLAY INVISIBLE (-1075 5575);
FORCEPROP 1 LAST PART_NUMBER TMP_QCS21002JB34
J 2
(-1075 5550);
DISPLAY 0.489362 (-1075 5550);
PAINT SKYBLUE (-1075 5550);
DISPLAY INVISIBLE (-1075 5550);
FORCEPROP 1 LAST WATTAGE 1/16W
J 2
(-1075 5625);
DISPLAY 0.489362 (-1075 5625);
PAINT SKYBLUE (-1075 5625);
DISPLAY INVISIBLE (-1075 5625);
FORCEPROP 1 LAST PATH I191
J 2
(-1075 5800);
DISPLAY 0.978723 (-1075 5800);
PAINT WHITE (-1075 5800);
DISPLAY INVISIBLE (-1075 5800);
FORCEPROP 2 LAST CDS_LIB pure_quanta
J 0
(-1025 5625);
DISPLAY INVISIBLE (-1025 5625);
FORCEADD UNIVERSAL_POWER..1
(-6225 4100);
FORCEPROP 3 LASTPIN (-6225 4050) SIG_NAME PVDD18_S5_P0\g
J 0
(-6215 4060);
DISPLAY 0.659574 (-6215 4060);
PAINT MONO (-6215 4060);
DISPLAY INVISIBLE (-6215 4060);
FORCEPROP 1 LAST HDL_POWER PVDD18_S5_P0
J 1
(-6225 4150);
DISPLAY 0.489362 (-6225 4150);
PAINT GREEN (-6225 4150);
FORCEPROP 2 LAST CDS_LIB pure_quanta_power
J 0
(-6225 4100);
DISPLAY INVISIBLE (-6225 4100);
FORCEPROP 1 LAST PATH I192
J 0
(-6175 4125);
DISPLAY 0.872340 (-6175 4125);
PAINT AQUA (-6175 4125);
DISPLAY INVISIBLE (-6175 4125);
FORCEADD Q_RES..1
(-4075 2325);
FORCEPROP 1 LAST LOCATION R606
J 0
(-3975 2325);
DISPLAY 0.489362 (-3975 2325);
PAINT SKYBLUE (-3975 2325);
FORCEPROP 0 LAST $SEC 1
J 0
(-3975 2350);
DISPLAY 0.680851 (-3975 2350);
PAINT MONO (-3975 2350);
DISPLAY INVISIBLE (-3975 2350);
FORCEPROP 0 LAST CDS_SEC 1
J 0
(-3975 2350);
DISPLAY 1.021277 (-3975 2350);
DISPLAY INVISIBLE (-3975 2350);
FORCEPROP 1 LASTPIN (-4175 2325) $PN 1
J 0
(-4163 2337);
DISPLAY 0.489362 (-4163 2337);
PAINT MONO (-4163 2337);
FORCEPROP 1 LASTPIN (-3975 2325) $PN 2
J 0
(-4013 2337);
DISPLAY 0.489362 (-4013 2337);
PAINT MONO (-4013 2337);
FORCEPROP 1 LAST VALUE 0
J 2
(-4175 2325);
DISPLAY 0.489362 (-4175 2325);
PAINT SKYBLUE (-4175 2325);
FORCEPROP 1 LAST PATH I205
J 0
(-4125 2475);
DISPLAY 0.978723 (-4125 2475);
PAINT WHITE (-4125 2475);
DISPLAY INVISIBLE (-4125 2475);
FORCEPROP 1 LAST PACK_TYPE 0402LF
J 0
(-4025 2250);
DISPLAY 0.489362 (-4025 2250);
PAINT SKYBLUE (-4025 2250);
DISPLAY INVISIBLE (-4025 2250);
FORCEPROP 1 LAST PART_NUMBER CS00002JB38
J 0
(-4050 2375);
DISPLAY 0.489362 (-4050 2375);
PAINT SKYBLUE (-4050 2375);
DISPLAY INVISIBLE (-4050 2375);
FORCEPROP 1 LAST TOLERANCE 5%
J 0
(-4100 2250);
DISPLAY 0.489362 (-4100 2250);
PAINT SKYBLUE (-4100 2250);
DISPLAY INVISIBLE (-4100 2250);
FORCEPROP 1 LAST MATERIAL CHIP
J 0
(-3650 2250);
DISPLAY 0.489362 (-3650 2250);
PAINT SKYBLUE (-3650 2250);
DISPLAY INVISIBLE (-3650 2250);
FORCEPROP 1 LAST WATTAGE 1/16W
J 2
(-3675 2250);
DISPLAY 0.489362 (-3675 2250);
PAINT SKYBLUE (-3675 2250);
DISPLAY INVISIBLE (-3675 2250);
FORCEPROP 2 LAST CDS_LIB pure_quanta
J 0
(-4075 2325);
DISPLAY INVISIBLE (-4075 2325);
FORCEADD OFFPAGE..3
(-3125 2325);
FORCEPROP 2 LAST $XR1 117 
J 0
(-2821 2325);
DISPLAY 0.638298 (-2821 2325);
PAINT MONO (-2821 2325);
FORCEPROP 2 LAST $XR0 76 
J 0
(-2911 2325);
DISPLAY 0.638298 (-2911 2325);
PAINT MONO (-2911 2325);
FORCEPROP 2 LAST PATH I206
J 0
(-2800 2375);
DISPLAY 0.680851 (-2800 2375);
DISPLAY INVISIBLE (-2800 2375);
FORCEPROP 1 LAST COMMENT_BODY TRUE
J 0
(-3175 2225);
DISPLAY 0.872340 (-3175 2225);
PAINT PEACH (-3175 2225);
DISPLAY INVISIBLE (-3175 2225);
FORCEPROP 1 LAST OFFPAGE TRUE
J 0
(-2800 2200);
DISPLAY 0.872340 (-2800 2200);
PAINT GREEN (-2800 2200);
DISPLAY INVISIBLE (-2800 2200);
FORCEPROP 2 LAST CDS_LIB standard
J 0
(-3125 2325);
DISPLAY INVISIBLE (-3125 2325);
FORCEADD Q_RES..1
(-4075 2375);
FORCEPROP 1 LAST LOCATION R607
J 0
(-3975 2375);
DISPLAY 0.489362 (-3975 2375);
PAINT SKYBLUE (-3975 2375);
FORCEPROP 0 LAST $SEC 1
J 0
(-3975 2400);
DISPLAY 0.680851 (-3975 2400);
PAINT MONO (-3975 2400);
DISPLAY INVISIBLE (-3975 2400);
FORCEPROP 0 LAST CDS_SEC 1
J 0
(-3975 2400);
DISPLAY 1.021277 (-3975 2400);
DISPLAY INVISIBLE (-3975 2400);
FORCEPROP 1 LASTPIN (-4175 2375) $PN 1
J 0
(-4163 2387);
DISPLAY 0.489362 (-4163 2387);
PAINT MONO (-4163 2387);
FORCEPROP 1 LASTPIN (-3975 2375) $PN 2
J 0
(-4013 2387);
DISPLAY 0.489362 (-4013 2387);
PAINT MONO (-4013 2387);
FORCEPROP 1 LAST VALUE 0
J 2
(-4175 2375);
DISPLAY 0.489362 (-4175 2375);
PAINT SKYBLUE (-4175 2375);
FORCEPROP 1 LAST PATH I207
J 0
(-4125 2525);
DISPLAY 0.978723 (-4125 2525);
PAINT WHITE (-4125 2525);
DISPLAY INVISIBLE (-4125 2525);
FORCEPROP 1 LAST WATTAGE 1/16W
J 2
(-3675 2300);
DISPLAY 0.489362 (-3675 2300);
PAINT SKYBLUE (-3675 2300);
DISPLAY INVISIBLE (-3675 2300);
FORCEPROP 1 LAST MATERIAL CHIP
J 0
(-3650 2300);
DISPLAY 0.489362 (-3650 2300);
PAINT SKYBLUE (-3650 2300);
DISPLAY INVISIBLE (-3650 2300);
FORCEPROP 1 LAST TOLERANCE 5%
J 0
(-4100 2300);
DISPLAY 0.489362 (-4100 2300);
PAINT SKYBLUE (-4100 2300);
DISPLAY INVISIBLE (-4100 2300);
FORCEPROP 1 LAST PART_NUMBER CS00002JB38
J 0
(-4050 2425);
DISPLAY 0.489362 (-4050 2425);
PAINT SKYBLUE (-4050 2425);
DISPLAY INVISIBLE (-4050 2425);
FORCEPROP 1 LAST PACK_TYPE 0402LF
J 0
(-4025 2300);
DISPLAY 0.489362 (-4025 2300);
PAINT SKYBLUE (-4025 2300);
DISPLAY INVISIBLE (-4025 2300);
FORCEPROP 2 LAST CDS_LIB pure_quanta
J 0
(-4075 2375);
DISPLAY INVISIBLE (-4075 2375);
FORCEADD OFFPAGE..3
(-3125 2375);
FORCEPROP 2 LAST $XR1 117 
J 0
(-2821 2375);
DISPLAY 0.638298 (-2821 2375);
PAINT MONO (-2821 2375);
FORCEPROP 2 LAST $XR0 76 
J 0
(-2911 2375);
DISPLAY 0.638298 (-2911 2375);
PAINT MONO (-2911 2375);
FORCEPROP 2 LAST PATH I208
J 0
(-2800 2425);
DISPLAY 0.680851 (-2800 2425);
DISPLAY INVISIBLE (-2800 2425);
FORCEPROP 1 LAST COMMENT_BODY TRUE
J 0
(-3175 2275);
DISPLAY 0.872340 (-3175 2275);
PAINT PEACH (-3175 2275);
DISPLAY INVISIBLE (-3175 2275);
FORCEPROP 1 LAST OFFPAGE TRUE
J 0
(-2800 2250);
DISPLAY 0.872340 (-2800 2250);
PAINT GREEN (-2800 2250);
DISPLAY INVISIBLE (-2800 2250);
FORCEPROP 2 LAST CDS_LIB standard
J 0
(-3125 2375);
DISPLAY INVISIBLE (-3125 2375);
FORCEADD OFFPAGE..3
R 2
(-6925 2325);
FORCEPROP 2 LAST $XR1 76 
J 0
(-7294 2325);
DISPLAY 0.638298 (-7294 2325);
PAINT MONO (-7294 2325);
FORCEPROP 2 LAST $XR0 29 
J 0
(-7204 2325);
DISPLAY 0.638298 (-7204 2325);
PAINT MONO (-7204 2325);
FORCEPROP 2 LAST PATH I214
J 0
(-7200 2375);
DISPLAY 0.680851 (-7200 2375);
DISPLAY INVISIBLE (-7200 2375);
FORCEPROP 1 LAST COMMENT_BODY TRUE
J 2
(-6875 2225);
DISPLAY 0.872340 (-6875 2225);
PAINT PEACH (-6875 2225);
DISPLAY INVISIBLE (-6875 2225);
FORCEPROP 1 LAST OFFPAGE TRUE
J 2
(-7250 2200);
DISPLAY 0.872340 (-7250 2200);
PAINT GREEN (-7250 2200);
DISPLAY INVISIBLE (-7250 2200);
FORCEPROP 2 LAST CDS_LIB standard
J 0
(-6925 2325);
DISPLAY INVISIBLE (-6925 2325);
FORCEADD OFFPAGE..3
R 2
(-6925 2375);
FORCEPROP 2 LAST $XR1 76 
J 0
(-7294 2375);
DISPLAY 0.638298 (-7294 2375);
PAINT MONO (-7294 2375);
FORCEPROP 2 LAST $XR0 29 
J 0
(-7204 2375);
DISPLAY 0.638298 (-7204 2375);
PAINT MONO (-7204 2375);
FORCEPROP 2 LAST PATH I215
J 0
(-7200 2425);
DISPLAY 0.680851 (-7200 2425);
DISPLAY INVISIBLE (-7200 2425);
FORCEPROP 1 LAST COMMENT_BODY TRUE
J 2
(-6875 2275);
DISPLAY 0.872340 (-6875 2275);
PAINT PEACH (-6875 2275);
DISPLAY INVISIBLE (-6875 2275);
FORCEPROP 1 LAST OFFPAGE TRUE
J 2
(-7250 2250);
DISPLAY 0.872340 (-7250 2250);
PAINT GREEN (-7250 2250);
DISPLAY INVISIBLE (-7250 2250);
FORCEPROP 2 LAST CDS_LIB standard
J 0
(-6925 2375);
DISPLAY INVISIBLE (-6925 2375);
FORCEADD OFFPAGE..3
(-3125 2225);
FORCEPROP 2 LAST $XR1 117 
J 0
(-2821 2225);
DISPLAY 0.638298 (-2821 2225);
PAINT MONO (-2821 2225);
FORCEPROP 2 LAST $XR0 76 
J 0
(-2911 2225);
DISPLAY 0.638298 (-2911 2225);
PAINT MONO (-2911 2225);
FORCEPROP 2 LAST CDS_LIB standard
J 2
(-3125 2225);
DISPLAY INVISIBLE (-3125 2225);
FORCEPROP 1 LAST OFFPAGE TRUE
J 0
(-2800 2100);
DISPLAY 0.872340 (-2800 2100);
PAINT GREEN (-2800 2100);
DISPLAY INVISIBLE (-2800 2100);
FORCEPROP 1 LAST COMMENT_BODY TRUE
J 0
(-3175 2125);
DISPLAY 0.872340 (-3175 2125);
PAINT PEACH (-3175 2125);
DISPLAY INVISIBLE (-3175 2125);
FORCEPROP 2 LAST PATH I218
J 0
(-2800 2275);
DISPLAY 0.680851 (-2800 2275);
DISPLAY INVISIBLE (-2800 2275);
FORCEADD Q_RES..1
(-4075 2225);
FORCEPROP 1 LAST LOCATION R605
J 0
(-3975 2225);
DISPLAY 0.489362 (-3975 2225);
PAINT SKYBLUE (-3975 2225);
FORCEPROP 0 LAST $SEC 1
J 0
(-3975 2250);
DISPLAY 0.680851 (-3975 2250);
PAINT MONO (-3975 2250);
DISPLAY INVISIBLE (-3975 2250);
FORCEPROP 0 LAST CDS_SEC 1
J 0
(-3975 2250);
DISPLAY 1.021277 (-3975 2250);
DISPLAY INVISIBLE (-3975 2250);
FORCEPROP 1 LASTPIN (-4175 2225) $PN 1
J 0
(-4163 2237);
DISPLAY 0.489362 (-4163 2237);
PAINT MONO (-4163 2237);
FORCEPROP 1 LASTPIN (-3975 2225) $PN 2
J 0
(-4013 2237);
DISPLAY 0.489362 (-4013 2237);
PAINT MONO (-4013 2237);
FORCEPROP 1 LAST VALUE 0
J 2
(-4175 2225);
DISPLAY 0.489362 (-4175 2225);
PAINT SKYBLUE (-4175 2225);
FORCEPROP 2 LAST CDS_LIB pure_quanta
J 0
(-4075 2225);
DISPLAY INVISIBLE (-4075 2225);
FORCEPROP 1 LAST WATTAGE 1/16W
J 2
(-3675 2150);
DISPLAY 0.489362 (-3675 2150);
PAINT SKYBLUE (-3675 2150);
DISPLAY INVISIBLE (-3675 2150);
FORCEPROP 1 LAST MATERIAL CHIP
J 0
(-3650 2150);
DISPLAY 0.489362 (-3650 2150);
PAINT SKYBLUE (-3650 2150);
DISPLAY INVISIBLE (-3650 2150);
FORCEPROP 1 LAST TOLERANCE 5%
J 0
(-4100 2150);
DISPLAY 0.489362 (-4100 2150);
PAINT SKYBLUE (-4100 2150);
DISPLAY INVISIBLE (-4100 2150);
FORCEPROP 1 LAST PART_NUMBER CS00002JB38
J 0
(-4050 2275);
DISPLAY 0.489362 (-4050 2275);
PAINT SKYBLUE (-4050 2275);
DISPLAY INVISIBLE (-4050 2275);
FORCEPROP 1 LAST PACK_TYPE 0402LF
J 0
(-4025 2150);
DISPLAY 0.489362 (-4025 2150);
PAINT SKYBLUE (-4025 2150);
DISPLAY INVISIBLE (-4025 2150);
FORCEPROP 1 LAST PATH I219
J 0
(-4125 2375);
DISPLAY 0.978723 (-4125 2375);
PAINT WHITE (-4125 2375);
DISPLAY INVISIBLE (-4125 2375);
FORCEADD OFFPAGE..3
(-3125 2275);
FORCEPROP 2 LAST $XR1 117 
J 0
(-2821 2275);
DISPLAY 0.638298 (-2821 2275);
PAINT MONO (-2821 2275);
FORCEPROP 2 LAST $XR0 76 
J 0
(-2911 2275);
DISPLAY 0.638298 (-2911 2275);
PAINT MONO (-2911 2275);
FORCEPROP 2 LAST CDS_LIB standard
J 2
(-3125 2275);
DISPLAY INVISIBLE (-3125 2275);
FORCEPROP 1 LAST OFFPAGE TRUE
J 0
(-2800 2150);
DISPLAY 0.872340 (-2800 2150);
PAINT GREEN (-2800 2150);
DISPLAY INVISIBLE (-2800 2150);
FORCEPROP 1 LAST COMMENT_BODY TRUE
J 0
(-3175 2175);
DISPLAY 0.872340 (-3175 2175);
PAINT PEACH (-3175 2175);
DISPLAY INVISIBLE (-3175 2175);
FORCEPROP 2 LAST PATH I220
J 0
(-2800 2325);
DISPLAY 0.680851 (-2800 2325);
DISPLAY INVISIBLE (-2800 2325);
FORCEADD Q_RES..1
(-4075 2275);
FORCEPROP 1 LAST LOCATION R604
J 0
(-3975 2275);
DISPLAY 0.489362 (-3975 2275);
PAINT SKYBLUE (-3975 2275);
FORCEPROP 0 LAST $SEC 1
J 0
(-3975 2300);
DISPLAY 0.680851 (-3975 2300);
PAINT MONO (-3975 2300);
DISPLAY INVISIBLE (-3975 2300);
FORCEPROP 0 LAST CDS_SEC 1
J 0
(-3975 2300);
DISPLAY 1.021277 (-3975 2300);
DISPLAY INVISIBLE (-3975 2300);
FORCEPROP 1 LASTPIN (-4175 2275) $PN 1
J 0
(-4163 2287);
DISPLAY 0.489362 (-4163 2287);
PAINT MONO (-4163 2287);
FORCEPROP 1 LASTPIN (-3975 2275) $PN 2
J 0
(-4013 2287);
DISPLAY 0.489362 (-4013 2287);
PAINT MONO (-4013 2287);
FORCEPROP 1 LAST VALUE 0
J 2
(-4175 2275);
DISPLAY 0.489362 (-4175 2275);
PAINT SKYBLUE (-4175 2275);
FORCEPROP 2 LAST CDS_LIB pure_quanta
J 0
(-4075 2275);
DISPLAY INVISIBLE (-4075 2275);
FORCEPROP 1 LAST WATTAGE 1/16W
J 2
(-3675 2200);
DISPLAY 0.489362 (-3675 2200);
PAINT SKYBLUE (-3675 2200);
DISPLAY INVISIBLE (-3675 2200);
FORCEPROP 1 LAST MATERIAL CHIP
J 0
(-3650 2200);
DISPLAY 0.489362 (-3650 2200);
PAINT SKYBLUE (-3650 2200);
DISPLAY INVISIBLE (-3650 2200);
FORCEPROP 1 LAST TOLERANCE 5%
J 0
(-4100 2200);
DISPLAY 0.489362 (-4100 2200);
PAINT SKYBLUE (-4100 2200);
DISPLAY INVISIBLE (-4100 2200);
FORCEPROP 1 LAST PART_NUMBER CS00002JB38
J 0
(-4050 2325);
DISPLAY 0.489362 (-4050 2325);
PAINT SKYBLUE (-4050 2325);
DISPLAY INVISIBLE (-4050 2325);
FORCEPROP 1 LAST PACK_TYPE 0402LF
J 0
(-4025 2200);
DISPLAY 0.489362 (-4025 2200);
PAINT SKYBLUE (-4025 2200);
DISPLAY INVISIBLE (-4025 2200);
FORCEPROP 1 LAST PATH I221
J 0
(-4125 2425);
DISPLAY 0.978723 (-4125 2425);
PAINT WHITE (-4125 2425);
DISPLAY INVISIBLE (-4125 2425);
FORCEADD OFFPAGE..3
R 2
(-6925 2225);
FORCEPROP 2 LAST $XR1 76 
J 0
(-7294 2225);
DISPLAY 0.638298 (-7294 2225);
PAINT MONO (-7294 2225);
FORCEPROP 2 LAST $XR0 29 
J 0
(-7204 2225);
DISPLAY 0.638298 (-7204 2225);
PAINT MONO (-7204 2225);
FORCEPROP 1 LAST COMMENT_BODY TRUE
J 2
(-6875 2125);
DISPLAY 0.872340 (-6875 2125);
PAINT PEACH (-6875 2125);
DISPLAY INVISIBLE (-6875 2125);
FORCEPROP 1 LAST OFFPAGE TRUE
J 2
(-7250 2100);
DISPLAY 0.872340 (-7250 2100);
PAINT GREEN (-7250 2100);
DISPLAY INVISIBLE (-7250 2100);
FORCEPROP 2 LAST CDS_LIB standard
J 2
(-6925 2225);
DISPLAY INVISIBLE (-6925 2225);
FORCEPROP 2 LAST PATH I223
J 0
(-7200 2275);
DISPLAY 0.680851 (-7200 2275);
DISPLAY INVISIBLE (-7200 2275);
FORCEADD OFFPAGE..3
R 2
(-6925 2275);
FORCEPROP 2 LAST $XR1 76 
J 0
(-7294 2275);
DISPLAY 0.638298 (-7294 2275);
PAINT MONO (-7294 2275);
FORCEPROP 2 LAST $XR0 29 
J 0
(-7204 2275);
DISPLAY 0.638298 (-7204 2275);
PAINT MONO (-7204 2275);
FORCEPROP 1 LAST COMMENT_BODY TRUE
J 2
(-6875 2175);
DISPLAY 0.872340 (-6875 2175);
PAINT PEACH (-6875 2175);
DISPLAY INVISIBLE (-6875 2175);
FORCEPROP 1 LAST OFFPAGE TRUE
J 2
(-7250 2150);
DISPLAY 0.872340 (-7250 2150);
PAINT GREEN (-7250 2150);
DISPLAY INVISIBLE (-7250 2150);
FORCEPROP 2 LAST CDS_LIB standard
J 2
(-6925 2275);
DISPLAY INVISIBLE (-6925 2275);
FORCEPROP 2 LAST PATH I224
J 0
(-7200 2325);
DISPLAY 0.680851 (-7200 2325);
DISPLAY INVISIBLE (-7200 2325);
FORCEADD OFFPAGE..2
(-3000 4325);
FORCEPROP 2 LAST $XR1 117 
J 0
(-2721 4325);
DISPLAY 0.638298 (-2721 4325);
PAINT MONO (-2721 4325);
FORCEPROP 2 LAST $XR0 76 
J 0
(-2811 4325);
DISPLAY 0.638298 (-2811 4325);
PAINT MONO (-2811 4325);
FORCEPROP 2 LAST CDS_LIB standard
J 0
(-3000 4325);
DISPLAY INVISIBLE (-3000 4325);
FORCEPROP 1 LAST OFFPAGE TRUE
J 0
(-2675 4200);
DISPLAY 0.872340 (-2675 4200);
PAINT GREEN (-2675 4200);
DISPLAY INVISIBLE (-2675 4200);
FORCEPROP 1 LAST COMMENT_BODY TRUE
J 0
(-3045 4230);
DISPLAY 0.872340 (-3045 4230);
PAINT PEACH (-3045 4230);
DISPLAY INVISIBLE (-3045 4230);
FORCEPROP 2 LAST PATH I227
J 0
(-2700 4375);
DISPLAY 0.680851 (-2700 4375);
DISPLAY INVISIBLE (-2700 4375);
FORCEADD Q_RES..1
(-3950 4325);
FORCEPROP 1 LAST LOCATION R603
J 0
(-3850 4325);
DISPLAY 0.489362 (-3850 4325);
PAINT SKYBLUE (-3850 4325);
FORCEPROP 0 LAST $SEC 1
J 0
(-3850 4350);
DISPLAY 0.680851 (-3850 4350);
PAINT MONO (-3850 4350);
DISPLAY INVISIBLE (-3850 4350);
FORCEPROP 0 LAST CDS_SEC 1
J 0
(-3850 4350);
DISPLAY 1.021277 (-3850 4350);
DISPLAY INVISIBLE (-3850 4350);
FORCEPROP 1 LASTPIN (-4050 4325) $PN 1
J 0
(-4038 4337);
DISPLAY 0.489362 (-4038 4337);
PAINT MONO (-4038 4337);
FORCEPROP 1 LASTPIN (-3850 4325) $PN 2
J 0
(-3888 4337);
DISPLAY 0.489362 (-3888 4337);
PAINT MONO (-3888 4337);
FORCEPROP 1 LAST VALUE 0
J 2
(-4050 4325);
DISPLAY 0.489362 (-4050 4325);
PAINT SKYBLUE (-4050 4325);
FORCEPROP 2 LAST CDS_LIB pure_quanta
J 0
(-3950 4325);
DISPLAY INVISIBLE (-3950 4325);
FORCEPROP 1 LAST WATTAGE 1/16W
J 2
(-3550 4250);
DISPLAY 0.489362 (-3550 4250);
PAINT SKYBLUE (-3550 4250);
DISPLAY INVISIBLE (-3550 4250);
FORCEPROP 1 LAST MATERIAL CHIP
J 0
(-3525 4250);
DISPLAY 0.489362 (-3525 4250);
PAINT SKYBLUE (-3525 4250);
DISPLAY INVISIBLE (-3525 4250);
FORCEPROP 1 LAST TOLERANCE 5%
J 0
(-3975 4250);
DISPLAY 0.489362 (-3975 4250);
PAINT SKYBLUE (-3975 4250);
DISPLAY INVISIBLE (-3975 4250);
FORCEPROP 1 LAST PART_NUMBER CS00002JB38
J 0
(-3925 4375);
DISPLAY 0.489362 (-3925 4375);
PAINT SKYBLUE (-3925 4375);
DISPLAY INVISIBLE (-3925 4375);
FORCEPROP 1 LAST PACK_TYPE 0402LF
J 0
(-3900 4250);
DISPLAY 0.489362 (-3900 4250);
PAINT SKYBLUE (-3900 4250);
DISPLAY INVISIBLE (-3900 4250);
FORCEPROP 1 LAST PATH I228
J 0
(-4000 4475);
DISPLAY 0.978723 (-4000 4475);
PAINT WHITE (-4000 4475);
DISPLAY INVISIBLE (-4000 4475);
FORCEADD OFFPAGE..2
(-3000 4275);
FORCEPROP 2 LAST $XR1 117 
J 0
(-2721 4275);
DISPLAY 0.638298 (-2721 4275);
PAINT MONO (-2721 4275);
FORCEPROP 2 LAST $XR0 76 
J 0
(-2811 4275);
DISPLAY 0.638298 (-2811 4275);
PAINT MONO (-2811 4275);
FORCEPROP 2 LAST CDS_LIB standard
J 0
(-3000 4275);
DISPLAY INVISIBLE (-3000 4275);
FORCEPROP 1 LAST OFFPAGE TRUE
J 0
(-2675 4150);
DISPLAY 0.872340 (-2675 4150);
PAINT GREEN (-2675 4150);
DISPLAY INVISIBLE (-2675 4150);
FORCEPROP 1 LAST COMMENT_BODY TRUE
J 0
(-3045 4180);
DISPLAY 0.872340 (-3045 4180);
PAINT PEACH (-3045 4180);
DISPLAY INVISIBLE (-3045 4180);
FORCEPROP 2 LAST PATH I229
J 0
(-2700 4325);
DISPLAY 0.680851 (-2700 4325);
DISPLAY INVISIBLE (-2700 4325);
FORCEADD Q_RES..1
(-3950 4275);
FORCEPROP 1 LAST LOCATION R602
J 0
(-3850 4275);
DISPLAY 0.489362 (-3850 4275);
PAINT SKYBLUE (-3850 4275);
FORCEPROP 0 LAST $SEC 1
J 0
(-3850 4300);
DISPLAY 0.680851 (-3850 4300);
PAINT MONO (-3850 4300);
DISPLAY INVISIBLE (-3850 4300);
FORCEPROP 0 LAST CDS_SEC 1
J 0
(-3850 4300);
DISPLAY 1.021277 (-3850 4300);
DISPLAY INVISIBLE (-3850 4300);
FORCEPROP 1 LASTPIN (-4050 4275) $PN 1
J 0
(-4038 4287);
DISPLAY 0.489362 (-4038 4287);
PAINT MONO (-4038 4287);
FORCEPROP 1 LASTPIN (-3850 4275) $PN 2
J 0
(-3888 4287);
DISPLAY 0.489362 (-3888 4287);
PAINT MONO (-3888 4287);
FORCEPROP 1 LAST VALUE 0
J 2
(-4050 4275);
DISPLAY 0.489362 (-4050 4275);
PAINT SKYBLUE (-4050 4275);
FORCEPROP 2 LAST CDS_LIB pure_quanta
J 0
(-3950 4275);
DISPLAY INVISIBLE (-3950 4275);
FORCEPROP 1 LAST WATTAGE 1/16W
J 2
(-3550 4200);
DISPLAY 0.489362 (-3550 4200);
PAINT SKYBLUE (-3550 4200);
DISPLAY INVISIBLE (-3550 4200);
FORCEPROP 1 LAST MATERIAL CHIP
J 0
(-3525 4200);
DISPLAY 0.489362 (-3525 4200);
PAINT SKYBLUE (-3525 4200);
DISPLAY INVISIBLE (-3525 4200);
FORCEPROP 1 LAST TOLERANCE 5%
J 0
(-3975 4200);
DISPLAY 0.489362 (-3975 4200);
PAINT SKYBLUE (-3975 4200);
DISPLAY INVISIBLE (-3975 4200);
FORCEPROP 1 LAST PART_NUMBER CS00002JB38
J 0
(-3925 4325);
DISPLAY 0.489362 (-3925 4325);
PAINT SKYBLUE (-3925 4325);
DISPLAY INVISIBLE (-3925 4325);
FORCEPROP 1 LAST PACK_TYPE 0402LF
J 0
(-3900 4200);
DISPLAY 0.489362 (-3900 4200);
PAINT SKYBLUE (-3900 4200);
DISPLAY INVISIBLE (-3900 4200);
FORCEPROP 1 LAST PATH I230
J 0
(-4000 4425);
DISPLAY 0.978723 (-4000 4425);
PAINT WHITE (-4000 4425);
DISPLAY INVISIBLE (-4000 4425);
FORCEADD OFFPAGE..1
(-6800 4325);
FORCEPROP 2 LAST $XR1 76 
J 0
(-7141 4325);
DISPLAY 0.638298 (-7141 4325);
PAINT MONO (-7141 4325);
FORCEPROP 2 LAST $XR0 29 
J 0
(-7051 4325);
DISPLAY 0.638298 (-7051 4325);
PAINT MONO (-7051 4325);
FORCEPROP 1 LAST COMMENT_BODY TRUE
J 0
(-6670 4225);
DISPLAY 1.106383 (-6670 4225);
PAINT PEACH (-6670 4225);
DISPLAY INVISIBLE (-6670 4225);
FORCEPROP 1 LAST OFFPAGE TRUE
J 0
(-6470 4195);
PAINT GREEN (-6470 4195);
DISPLAY INVISIBLE (-6470 4195);
FORCEPROP 2 LAST CDS_LIB standard
J 0
(-6800 4325);
DISPLAY INVISIBLE (-6800 4325);
FORCEPROP 2 LAST PATH I232
J 0
(-7050 4375);
DISPLAY 0.680851 (-7050 4375);
DISPLAY INVISIBLE (-7050 4375);
FORCEADD OFFPAGE..1
(-6800 4275);
FORCEPROP 2 LAST $XR1 144 
J 0
(-7171 4275);
DISPLAY 0.638298 (-7171 4275);
PAINT MONO (-7171 4275);
FORCEPROP 2 LAST $XR0 29 
J 0
(-7051 4275);
DISPLAY 0.638298 (-7051 4275);
PAINT MONO (-7051 4275);
FORCEPROP 2 LAST CDS_LIB standard
J 0
(-6800 4275);
DISPLAY INVISIBLE (-6800 4275);
FORCEPROP 1 LAST OFFPAGE TRUE
J 0
(-6470 4145);
PAINT GREEN (-6470 4145);
DISPLAY INVISIBLE (-6470 4145);
FORCEPROP 1 LAST COMMENT_BODY TRUE
J 0
(-6670 4175);
DISPLAY 1.106383 (-6670 4175);
PAINT PEACH (-6670 4175);
DISPLAY INVISIBLE (-6670 4175);
FORCEPROP 2 LAST PATH I233
J 0
(-7050 4325);
DISPLAY 0.680851 (-7050 4325);
DISPLAY INVISIBLE (-7050 4325);
FORCEADD UNIVERSAL_POWER..1
(-4875 5000);
FORCEPROP 3 LASTPIN (-4875 4950) SIG_NAME P3V3_STBY\g
J 0
(-4865 4960);
DISPLAY 0.659574 (-4865 4960);
PAINT MONO (-4865 4960);
DISPLAY INVISIBLE (-4865 4960);
FORCEPROP 1 LAST HDL_POWER P3V3_STBY
J 1
(-4875 5050);
DISPLAY 0.489362 (-4875 5050);
PAINT GREEN (-4875 5050);
FORCEPROP 1 LAST PATH I49
J 0
(-4825 5025);
DISPLAY 0.872340 (-4825 5025);
PAINT AQUA (-4825 5025);
DISPLAY INVISIBLE (-4825 5025);
FORCEPROP 2 LAST CDS_LIB pure_quanta_power
J 0
(-4875 5000);
DISPLAY INVISIBLE (-4875 5000);
FORCEADD Q_CAP..1
(-4750 4750);
FORCEPROP 1 LAST LOCATION C1104
J 0
(-4700 4850);
DISPLAY 0.489362 (-4700 4850);
PAINT SKYBLUE (-4700 4850);
FORCEPROP 0 LAST $SEC 1
J 0
(-4700 4875);
DISPLAY 0.680851 (-4700 4875);
PAINT MONO (-4700 4875);
DISPLAY INVISIBLE (-4700 4875);
FORCEPROP 0 LAST CDS_SEC 1
J 0
(-4700 4875);
DISPLAY 1.021277 (-4700 4875);
DISPLAY INVISIBLE (-4700 4875);
FORCEPROP 1 LASTPIN (-4750 4850) $PN 1
J 0
(-4740 4830);
DISPLAY 0.489362 (-4740 4830);
PAINT MONO (-4740 4830);
FORCEPROP 1 LASTPIN (-4750 4650) $PN 2
J 0
(-4740 4630);
DISPLAY 0.489362 (-4740 4630);
PAINT MONO (-4740 4630);
FORCEPROP 1 LAST TOLERANCE 10%
J 0
(-4700 4750);
DISPLAY 0.489362 (-4700 4750);
PAINT SKYBLUE (-4700 4750);
FORCEPROP 1 LAST VOLTAGE 25V
J 0
(-4700 4775);
DISPLAY 0.489362 (-4700 4775);
PAINT SKYBLUE (-4700 4775);
FORCEPROP 1 LAST MATERIAL X7R
J 0
(-4700 4725);
DISPLAY 0.489362 (-4700 4725);
PAINT SKYBLUE (-4700 4725);
FORCEPROP 1 LAST PART_NUMBER CH4104K1B00
J 0
(-4700 4700);
DISPLAY 0.489362 (-4700 4700);
PAINT SKYBLUE (-4700 4700);
FORCEPROP 1 LAST PACK_TYPE 0402
J 0
(-4700 4675);
DISPLAY 0.489362 (-4700 4675);
PAINT SKYBLUE (-4700 4675);
FORCEPROP 1 LAST VALUE 0.1UF
J 0
(-4700 4800);
DISPLAY 0.489362 (-4700 4800);
PAINT SKYBLUE (-4700 4800);
FORCEPROP 1 LAST PATH I50
J 0
(-4700 4900);
DISPLAY 0.978723 (-4700 4900);
PAINT WHITE (-4700 4900);
DISPLAY INVISIBLE (-4700 4900);
FORCEPROP 2 LAST CDS_LIB pure_quanta
J 2
(-4750 4750);
DISPLAY INVISIBLE (-4750 4750);
FORCEADD UNIVERSAL_GND..1
R 2
(-4750 4550);
FORCEPROP 3 LASTPIN (-4750 4600) SIG_NAME GND\g
J 0
(-4740 4610);
DISPLAY 0.659574 (-4740 4610);
PAINT MONO (-4740 4610);
DISPLAY INVISIBLE (-4740 4610);
FORCEPROP 1 LAST HDL_POWER GND
J 1
(-4775 4475);
DISPLAY 0.872340 (-4775 4475);
PAINT GREEN (-4775 4475);
DISPLAY INVISIBLE (-4775 4475);
FORCEPROP 1 LAST PATH I51
J 2
(-4825 4550);
DISPLAY 0.872340 (-4825 4550);
PAINT AQUA (-4825 4550);
DISPLAY INVISIBLE (-4825 4550);
FORCEPROP 2 LAST CDS_LIB pure_quanta_power
J 2
(-4750 4550);
DISPLAY INVISIBLE (-4750 4550);
FORCEADD UNIVERSAL_POWER..1
(-5975 4975);
FORCEPROP 3 LASTPIN (-5975 4925) SIG_NAME PVDD18_S5_P0\g
J 0
(-5965 4935);
DISPLAY 0.659574 (-5965 4935);
PAINT MONO (-5965 4935);
DISPLAY INVISIBLE (-5965 4935);
FORCEPROP 1 LAST HDL_POWER PVDD18_S5_P0
J 1
(-5975 5025);
DISPLAY 0.489362 (-5975 5025);
PAINT GREEN (-5975 5025);
FORCEPROP 1 LAST PATH I52
J 0
(-5925 5000);
DISPLAY 0.872340 (-5925 5000);
PAINT AQUA (-5925 5000);
DISPLAY INVISIBLE (-5925 5000);
FORCEPROP 2 LAST CDS_LIB pure_quanta_power
J 0
(-5975 4975);
DISPLAY INVISIBLE (-5975 4975);
FORCEADD Q_CAP..1
R 2
(-6100 4750);
FORCEPROP 1 LAST LOCATION C1102
J 2
(-6150 4825);
DISPLAY 0.489362 (-6150 4825);
PAINT SKYBLUE (-6150 4825);
FORCEPROP 2 LAST $SEC 1
J 0
(-6150 4950);
DISPLAY 0.680851 (-6150 4950);
PAINT MONO (-6150 4950);
DISPLAY INVISIBLE (-6150 4950);
FORCEPROP 2 LAST CDS_SEC 1
J 0
(-6150 4950);
DISPLAY 1.021277 (-6150 4950);
DISPLAY INVISIBLE (-6150 4950);
FORCEPROP 1 LASTPIN (-6100 4850) $PN 1
J 2
(-6110 4830);
DISPLAY 0.489362 (-6110 4830);
FORCEPROP 1 LASTPIN (-6100 4650) $PN 2
J 2
(-6110 4630);
DISPLAY 0.489362 (-6110 4630);
FORCEPROP 1 LAST PACK_TYPE 0402
J 2
(-6150 4675);
DISPLAY 0.489362 (-6150 4675);
PAINT SKYBLUE (-6150 4675);
FORCEPROP 1 LAST MATERIAL X7R
J 2
(-6150 4725);
DISPLAY 0.489362 (-6150 4725);
PAINT SKYBLUE (-6150 4725);
FORCEPROP 1 LAST VALUE 0.1UF
J 2
(-6150 4800);
DISPLAY 0.489362 (-6150 4800);
PAINT SKYBLUE (-6150 4800);
FORCEPROP 1 LAST VOLTAGE 25V
J 2
(-6150 4775);
DISPLAY 0.489362 (-6150 4775);
PAINT SKYBLUE (-6150 4775);
FORCEPROP 1 LAST TOLERANCE 10%
J 2
(-6150 4750);
DISPLAY 0.489362 (-6150 4750);
PAINT SKYBLUE (-6150 4750);
FORCEPROP 1 LAST PART_NUMBER CH4104K1B00
J 2
(-6150 4700);
DISPLAY 0.489362 (-6150 4700);
PAINT SKYBLUE (-6150 4700);
FORCEPROP 1 LAST PATH I53
J 2
(-6150 4900);
DISPLAY 0.978723 (-6150 4900);
PAINT WHITE (-6150 4900);
DISPLAY INVISIBLE (-6150 4900);
FORCEPROP 2 LAST CDS_LIB pure_quanta
J 0
(-6100 4750);
PAINT MONO (-6100 4750);
DISPLAY INVISIBLE (-6100 4750);
FORCEADD UNIVERSAL_GND..1
(-6100 4550);
FORCEPROP 3 LASTPIN (-6100 4600) SIG_NAME GND\g
J 0
(-6090 4610);
DISPLAY 0.659574 (-6090 4610);
PAINT MONO (-6090 4610);
DISPLAY INVISIBLE (-6090 4610);
FORCEPROP 1 LAST HDL_POWER GND
J 1
(-6075 4475);
DISPLAY 0.872340 (-6075 4475);
PAINT GREEN (-6075 4475);
DISPLAY INVISIBLE (-6075 4475);
FORCEPROP 1 LAST PATH I54
J 0
(-6025 4550);
DISPLAY 0.872340 (-6025 4550);
PAINT AQUA (-6025 4550);
DISPLAY INVISIBLE (-6025 4550);
FORCEPROP 2 LAST CDS_LIB pure_quanta_power
J 0
(-6100 4550);
PAINT MONO (-6100 4550);
DISPLAY INVISIBLE (-6100 4550);
FORCEADD UNIVERSAL_GND..1
R 2
(-4775 3550);
FORCEPROP 3 LASTPIN (-4775 3600) SIG_NAME GND\g
J 0
(-4765 3610);
DISPLAY 0.659574 (-4765 3610);
PAINT MONO (-4765 3610);
DISPLAY INVISIBLE (-4765 3610);
FORCEPROP 2 LAST CDS_LIB pure_quanta_power
J 0
(-4775 3550);
DISPLAY INVISIBLE (-4775 3550);
FORCEPROP 1 LAST PATH I56
J 2
(-4850 3550);
DISPLAY 0.872340 (-4850 3550);
PAINT AQUA (-4850 3550);
DISPLAY INVISIBLE (-4850 3550);
FORCEPROP 1 LAST HDL_POWER GND
J 1
(-4800 3475);
DISPLAY 0.702128 (-4800 3475);
PAINT GREEN (-4800 3475);
DISPLAY INVISIBLE (-4800 3475);
FORCEADD UNIVERSAL_POWER..1
(-4850 2900);
FORCEPROP 3 LASTPIN (-4850 2850) SIG_NAME P3V3_STBY\g
J 0
(-4840 2860);
DISPLAY 0.659574 (-4840 2860);
PAINT MONO (-4840 2860);
DISPLAY INVISIBLE (-4840 2860);
FORCEPROP 1 LAST HDL_POWER P3V3_STBY
J 1
(-4850 2950);
DISPLAY 0.489362 (-4850 2950);
PAINT GREEN (-4850 2950);
FORCEPROP 2 LAST CDS_LIB pure_quanta_power
J 0
(-4850 2900);
DISPLAY INVISIBLE (-4850 2900);
FORCEPROP 1 LAST PATH I57
J 0
(-4800 2925);
DISPLAY 0.872340 (-4800 2925);
PAINT AQUA (-4800 2925);
DISPLAY INVISIBLE (-4800 2925);
FORCEADD Q_CAP..1
(-4725 2650);
FORCEPROP 1 LAST LOCATION C1105
J 0
(-4675 2750);
DISPLAY 0.489362 (-4675 2750);
PAINT SKYBLUE (-4675 2750);
FORCEPROP 0 LAST $SEC 1
J 0
(-4675 2775);
DISPLAY 0.680851 (-4675 2775);
PAINT MONO (-4675 2775);
DISPLAY INVISIBLE (-4675 2775);
FORCEPROP 0 LAST CDS_SEC 1
J 0
(-4675 2775);
DISPLAY 1.021277 (-4675 2775);
DISPLAY INVISIBLE (-4675 2775);
FORCEPROP 1 LASTPIN (-4725 2750) $PN 1
J 0
(-4715 2730);
DISPLAY 0.489362 (-4715 2730);
PAINT MONO (-4715 2730);
FORCEPROP 1 LASTPIN (-4725 2550) $PN 2
J 0
(-4715 2530);
DISPLAY 0.489362 (-4715 2530);
PAINT MONO (-4715 2530);
FORCEPROP 1 LAST PACK_TYPE 0402
J 0
(-4675 2575);
DISPLAY 0.489362 (-4675 2575);
PAINT SKYBLUE (-4675 2575);
FORCEPROP 1 LAST TOLERANCE 10%
J 0
(-4675 2650);
DISPLAY 0.489362 (-4675 2650);
PAINT SKYBLUE (-4675 2650);
FORCEPROP 1 LAST VOLTAGE 25V
J 0
(-4675 2675);
DISPLAY 0.489362 (-4675 2675);
PAINT SKYBLUE (-4675 2675);
FORCEPROP 1 LAST MATERIAL X7R
J 0
(-4675 2625);
DISPLAY 0.489362 (-4675 2625);
PAINT SKYBLUE (-4675 2625);
FORCEPROP 1 LAST VALUE 0.1UF
J 0
(-4675 2700);
DISPLAY 0.489362 (-4675 2700);
PAINT SKYBLUE (-4675 2700);
FORCEPROP 1 LAST PART_NUMBER CH4104K1B00
J 0
(-4675 2600);
DISPLAY 0.489362 (-4675 2600);
PAINT SKYBLUE (-4675 2600);
FORCEPROP 2 LAST CDS_LIB pure_quanta
J 0
(-4725 2650);
DISPLAY INVISIBLE (-4725 2650);
FORCEPROP 1 LAST PATH I59
J 0
(-4675 2800);
DISPLAY 0.978723 (-4675 2800);
PAINT WHITE (-4675 2800);
DISPLAY INVISIBLE (-4675 2800);
FORCEADD UNIVERSAL_GND..1
R 2
(-4825 1700);
FORCEPROP 3 LASTPIN (-4825 1750) SIG_NAME GND\g
J 0
(-4815 1760);
DISPLAY 0.659574 (-4815 1760);
PAINT MONO (-4815 1760);
DISPLAY INVISIBLE (-4815 1760);
FORCEPROP 1 LAST HDL_POWER GND
J 1
(-4850 1625);
DISPLAY 0.702128 (-4850 1625);
PAINT GREEN (-4850 1625);
DISPLAY INVISIBLE (-4850 1625);
FORCEPROP 1 LAST PATH I62
J 2
(-4900 1700);
DISPLAY 0.872340 (-4900 1700);
PAINT AQUA (-4900 1700);
DISPLAY INVISIBLE (-4900 1700);
FORCEPROP 2 LAST CDS_LIB pure_quanta_power
J 0
(-4825 1700);
DISPLAY INVISIBLE (-4825 1700);
FORCEADD SN74AVC4T774PWR..1
(-5425 4175);
FORCEPROP 1 LAST LOCATION U53
J 0
(-5675 4725);
DISPLAY 0.574468 (-5675 4725);
PAINT SKYBLUE (-5675 4725);
FORCEPROP 0 LAST $SEC 1
J 0
(-5675 4875);
DISPLAY 0.680851 (-5675 4875);
PAINT MONO (-5675 4875);
DISPLAY INVISIBLE (-5675 4875);
FORCEPROP 0 LAST CDS_SEC 1
J 0
(-5650 4725);
DISPLAY 1.021277 (-5650 4725);
DISPLAY INVISIBLE (-5650 4725);
FORCEPROP 0 LASTPIN (-5825 4325) $PN 3
J 2
(-5835 4335);
DISPLAY 0.680851 (-5835 4335);
PAINT MONO (-5835 4335);
FORCEPROP 0 LASTPIN (-5825 4275) $PN 4
J 2
(-5835 4285);
DISPLAY 0.680851 (-5835 4285);
PAINT MONO (-5835 4285);
FORCEPROP 0 LASTPIN (-5825 4225) $PN 5
J 2
(-5835 4235);
DISPLAY 0.680851 (-5835 4235);
PAINT MONO (-5835 4235);
FORCEPROP 0 LASTPIN (-5825 4175) $PN 6
J 2
(-5835 4185);
DISPLAY 0.680851 (-5835 4185);
PAINT MONO (-5835 4185);
FORCEPROP 0 LASTPIN (-5025 4325) $PN 14
J 0
(-5015 4335);
DISPLAY 0.680851 (-5015 4335);
PAINT MONO (-5015 4335);
FORCEPROP 0 LASTPIN (-5025 4275) $PN 13
J 0
(-5015 4285);
DISPLAY 0.680851 (-5015 4285);
PAINT MONO (-5015 4285);
FORCEPROP 0 LASTPIN (-5025 4225) $PN 12
J 0
(-5015 4235);
DISPLAY 0.680851 (-5015 4235);
PAINT MONO (-5015 4235);
FORCEPROP 0 LASTPIN (-5025 4175) $PN 11
J 0
(-5015 4185);
DISPLAY 0.680851 (-5015 4185);
PAINT MONO (-5015 4185);
FORCEPROP 0 LASTPIN (-5825 4025) $PN 1
J 2
(-5835 4035);
DISPLAY 0.680851 (-5835 4035);
PAINT MONO (-5835 4035);
FORCEPROP 0 LASTPIN (-5825 3975) $PN 2
J 2
(-5835 3985);
DISPLAY 0.680851 (-5835 3985);
PAINT MONO (-5835 3985);
FORCEPROP 0 LASTPIN (-5825 3925) $PN 7
J 2
(-5835 3935);
DISPLAY 0.680851 (-5835 3935);
PAINT MONO (-5835 3935);
FORCEPROP 0 LASTPIN (-5825 3875) $PN 8
J 2
(-5835 3885);
DISPLAY 0.680851 (-5835 3885);
PAINT MONO (-5835 3885);
FORCEPROP 0 LASTPIN (-5025 3775) $PN 10
J 0
(-5015 3785);
DISPLAY 0.680851 (-5015 3785);
PAINT MONO (-5015 3785);
FORCEPROP 0 LASTPIN (-5825 3825) $PN 9
J 2
(-5835 3835);
DISPLAY 0.680851 (-5835 3835);
PAINT MONO (-5835 3835);
FORCEPROP 0 LASTPIN (-5825 4525) $PN 16
J 2
(-5835 4535);
DISPLAY 0.680851 (-5835 4535);
PAINT MONO (-5835 4535);
FORCEPROP 0 LASTPIN (-5025 4525) $PN 15
J 0
(-5015 4535);
DISPLAY 0.680851 (-5015 4535);
PAINT MONO (-5015 4535);
FORCEPROP 2 LAST VALUE SN74AVC4T774PWR
J 0
(-5675 4775);
DISPLAY 0.489362 (-5675 4775);
PAINT SKYBLUE (-5675 4775);
FORCEPROP 2 LAST PART_TYPE SMLF
J 0
(-5675 4825);
DISPLAY 1.021277 (-5675 4825);
FORCEPROP 1 LAST MATERIAL IC
J 0
(-5675 4650);
DISPLAY 0.468085 (-5675 4650);
PAINT SKYBLUE (-5675 4650);
FORCEPROP 1 LAST PART_NUMBER AL04T774K00
J 0
(-5675 4700);
DISPLAY 0.468085 (-5675 4700);
PAINT SKYBLUE (-5675 4700);
FORCEPROP 2 LAST CDS_LIB pure_quanta
J 0
(-5425 4175);
DISPLAY INVISIBLE (-5425 4175);
FORCEPROP 1 LAST NEEDS_NO_SIZE TRUE
J 0
(-5425 4175);
DISPLAY 0.723404 (-5425 4175);
PAINT GREEN (-5425 4175);
DISPLAY INVISIBLE (-5425 4175);
FORCEPROP 1 LAST PATH I63
J 0
(-5425 4175);
DISPLAY 0.723404 (-5425 4175);
PAINT GREEN (-5425 4175);
DISPLAY INVISIBLE (-5425 4175);
FORCEPROP 1 LAST CDS_LMAN_SYM_OUTLINE -250,450,250,-450
J 0
(-5425 4175);
DISPLAY 0.468085 (-5425 4175);
PAINT GREEN (-5425 4175);
DISPLAY INVISIBLE (-5425 4175);
FORCEADD UNIVERSAL_POWER..1
(-6075 2900);
FORCEPROP 3 LASTPIN (-6075 2850) SIG_NAME PVDD18_S5_P0\g
J 0
(-6065 2860);
DISPLAY 0.659574 (-6065 2860);
PAINT MONO (-6065 2860);
DISPLAY INVISIBLE (-6065 2860);
FORCEPROP 1 LAST HDL_POWER PVDD18_S5_P0
J 1
(-6075 2950);
DISPLAY 0.489362 (-6075 2950);
PAINT GREEN (-6075 2950);
FORCEPROP 2 LAST CDS_LIB pure_quanta_power
J 0
(-6075 2900);
DISPLAY INVISIBLE (-6075 2900);
FORCEPROP 1 LAST PATH I64
J 0
(-6025 2925);
DISPLAY 0.872340 (-6025 2925);
PAINT AQUA (-6025 2925);
DISPLAY INVISIBLE (-6025 2925);
FORCEADD Q_CAP..1
R 2
(-6200 2675);
FORCEPROP 1 LAST LOCATION C1103
J 2
(-6250 2775);
DISPLAY 0.489362 (-6250 2775);
PAINT SKYBLUE (-6250 2775);
FORCEPROP 0 LAST $SEC 1
J 0
(-6250 2800);
DISPLAY 0.680851 (-6250 2800);
PAINT MONO (-6250 2800);
DISPLAY INVISIBLE (-6250 2800);
FORCEPROP 0 LAST CDS_SEC 1
J 0
(-6250 2800);
DISPLAY 1.021277 (-6250 2800);
DISPLAY INVISIBLE (-6250 2800);
FORCEPROP 1 LASTPIN (-6200 2775) $PN 1
J 2
(-6210 2755);
DISPLAY 0.489362 (-6210 2755);
PAINT MONO (-6210 2755);
FORCEPROP 1 LASTPIN (-6200 2575) $PN 2
J 2
(-6210 2555);
DISPLAY 0.489362 (-6210 2555);
PAINT MONO (-6210 2555);
FORCEPROP 1 LAST PART_NUMBER CH4104K1B00
J 2
(-6250 2625);
DISPLAY 0.489362 (-6250 2625);
PAINT SKYBLUE (-6250 2625);
FORCEPROP 1 LAST VALUE 0.1UF
J 2
(-6250 2725);
DISPLAY 0.489362 (-6250 2725);
PAINT SKYBLUE (-6250 2725);
FORCEPROP 1 LAST VOLTAGE 25V
J 2
(-6250 2700);
DISPLAY 0.489362 (-6250 2700);
PAINT SKYBLUE (-6250 2700);
FORCEPROP 1 LAST TOLERANCE 10%
J 2
(-6250 2675);
DISPLAY 0.489362 (-6250 2675);
PAINT SKYBLUE (-6250 2675);
FORCEPROP 1 LAST MATERIAL X7R
J 2
(-6250 2650);
DISPLAY 0.489362 (-6250 2650);
PAINT SKYBLUE (-6250 2650);
FORCEPROP 1 LAST PACK_TYPE 0402
J 2
(-6250 2600);
DISPLAY 0.489362 (-6250 2600);
PAINT SKYBLUE (-6250 2600);
FORCEPROP 2 LAST CDS_LIB pure_quanta
J 0
(-6200 2675);
DISPLAY INVISIBLE (-6200 2675);
FORCEPROP 1 LAST PATH I65
J 2
(-6250 2825);
DISPLAY 0.978723 (-6250 2825);
PAINT WHITE (-6250 2825);
DISPLAY INVISIBLE (-6250 2825);
FORCEADD PI4ULS3V304AZMAEX..1
(-5550 2275);
FORCEPROP 1 LAST LOCATION U54
J 0
(-5800 2625);
DISPLAY 0.468085 (-5800 2625);
PAINT SKYBLUE (-5800 2625);
FORCEPROP 0 LAST $SEC 1
J 0
(-5800 2775);
DISPLAY 0.680851 (-5800 2775);
PAINT MONO (-5800 2775);
DISPLAY INVISIBLE (-5800 2775);
FORCEPROP 0 LAST CDS_SEC 1
J 0
(-5775 2825);
DISPLAY 1.021277 (-5775 2825);
DISPLAY INVISIBLE (-5775 2825);
FORCEPROP 0 LASTPIN (-5950 2375) $PN 2
J 2
(-5960 2385);
DISPLAY 0.680851 (-5960 2385);
PAINT MONO (-5960 2385);
FORCEPROP 0 LASTPIN (-5950 2325) $PN 3
J 2
(-5960 2335);
DISPLAY 0.680851 (-5960 2335);
PAINT MONO (-5960 2335);
FORCEPROP 0 LASTPIN (-5950 2275) $PN 4
J 2
(-5960 2285);
DISPLAY 0.680851 (-5960 2285);
PAINT MONO (-5960 2285);
FORCEPROP 0 LASTPIN (-5950 2225) $PN 5
J 2
(-5960 2235);
DISPLAY 0.680851 (-5960 2235);
PAINT MONO (-5960 2235);
FORCEPROP 0 LASTPIN (-5150 2375) $PN 10
J 0
(-5140 2385);
DISPLAY 0.680851 (-5140 2385);
PAINT MONO (-5140 2385);
FORCEPROP 0 LASTPIN (-5150 2325) $PN 9
J 0
(-5140 2335);
DISPLAY 0.680851 (-5140 2335);
PAINT MONO (-5140 2335);
FORCEPROP 0 LASTPIN (-5150 2275) $PN 8
J 0
(-5140 2285);
DISPLAY 0.680851 (-5140 2285);
PAINT MONO (-5140 2285);
FORCEPROP 0 LASTPIN (-5150 2225) $PN 7
J 0
(-5140 2235);
DISPLAY 0.680851 (-5140 2235);
PAINT MONO (-5140 2235);
FORCEPROP 0 LASTPIN (-5950 2125) $PN 12
J 2
(-5960 2135);
DISPLAY 0.680851 (-5960 2135);
PAINT MONO (-5960 2135);
FORCEPROP 0 LASTPIN (-5150 2125) $PN 6
J 0
(-5140 2135);
DISPLAY 0.680851 (-5140 2135);
PAINT MONO (-5140 2135);
FORCEPROP 0 LASTPIN (-5950 2475) $PN 1
J 2
(-5960 2485);
DISPLAY 0.680851 (-5960 2485);
PAINT MONO (-5960 2485);
FORCEPROP 0 LASTPIN (-5150 2475) $PN 11
J 0
(-5140 2485);
DISPLAY 0.680851 (-5140 2485);
PAINT MONO (-5140 2485);
FORCEPROP 2 LAST VALUE PI4ULS3V304AZMAEX
J 0
(-5800 2675);
DISPLAY 0.489362 (-5800 2675);
PAINT SKYBLUE (-5800 2675);
FORCEPROP 2 LAST PART_TYPE SMLF
J 0
(-5800 2725);
DISPLAY 1.021277 (-5800 2725);
FORCEPROP 1 LAST MATERIAL IC
J 0
(-5795 2557);
DISPLAY 0.468085 (-5795 2557);
PAINT SKYBLUE (-5795 2557);
FORCEPROP 1 LAST PART_NUMBER AL000304005
J 0
(-5800 2600);
DISPLAY 0.468085 (-5800 2600);
PAINT SKYBLUE (-5800 2600);
FORCEPROP 2 LAST CDS_LIB pure_quanta
J 0
(-5550 2275);
DISPLAY INVISIBLE (-5550 2275);
FORCEPROP 1 LAST NEEDS_NO_SIZE TRUE
J 0
(-5550 2275);
DISPLAY 0.723404 (-5550 2275);
PAINT GREEN (-5550 2275);
DISPLAY INVISIBLE (-5550 2275);
FORCEPROP 1 LAST PATH I67
J 0
(-5550 2275);
DISPLAY 0.723404 (-5550 2275);
PAINT GREEN (-5550 2275);
DISPLAY INVISIBLE (-5550 2275);
FORCEPROP 1 LAST CDS_LMAN_SYM_OUTLINE -250,250,250,-250
J 0
(-5550 2275);
DISPLAY 0.468085 (-5550 2275);
PAINT GREEN (-5550 2275);
DISPLAY INVISIBLE (-5550 2275);
FORCEADD UNIVERSAL_POWER..1
R 2
(-2225 5925);
FORCEPROP 3 LASTPIN (-2225 5875) SIG_NAME P3V3_STBY\g
J 0
(-2215 5885);
DISPLAY 0.659574 (-2215 5885);
PAINT MONO (-2215 5885);
DISPLAY INVISIBLE (-2215 5885);
FORCEPROP 1 LAST HDL_POWER P3V3_STBY
J 1
(-2225 5975);
DISPLAY 0.489362 (-2225 5975);
PAINT GREEN (-2225 5975);
FORCEPROP 2 LAST CDS_LIB pure_quanta_power
J 2
(-2225 5925);
DISPLAY INVISIBLE (-2225 5925);
FORCEPROP 1 LAST PATH I96
J 2
(-2275 5950);
DISPLAY 0.872340 (-2275 5950);
PAINT AQUA (-2275 5950);
DISPLAY INVISIBLE (-2275 5950);
FORCEADD Q_RES..2
R 2
(-2050 5625);
FORCEPROP 1 LAST LOCATION R610
J 0
(-2025 5725);
DISPLAY 0.489362 (-2025 5725);
PAINT SKYBLUE (-2025 5725);
FORCEPROP 0 LAST $SEC 1
J 2
(-2100 5775);
DISPLAY 0.680851 (-2100 5775);
PAINT MONO (-2100 5775);
DISPLAY INVISIBLE (-2100 5775);
FORCEPROP 0 LAST CDS_SEC 1
J 2
(-2100 5775);
DISPLAY 1.021277 (-2100 5775);
DISPLAY INVISIBLE (-2100 5775);
FORCEPROP 1 LASTPIN (-2050 5725) $PN 1
J 2
(-2055 5687);
DISPLAY 0.489362 (-2055 5687);
PAINT MONO (-2055 5687);
FORCEPROP 1 LASTPIN (-2050 5525) $PN 2
J 2
(-2055 5535);
DISPLAY 0.489362 (-2055 5535);
PAINT MONO (-2055 5535);
FORCEPROP 1 LAST TOLERANCE 5%
J 0
(-2025 5625);
DISPLAY 0.489362 (-2025 5625);
PAINT SKYBLUE (-2025 5625);
FORCEPROP 1 LAST VALUE 1K
J 0
(-2025 5675);
DISPLAY 0.489362 (-2025 5675);
PAINT SKYBLUE (-2025 5675);
FORCEPROP 1 LAST MATERIAL EMPTY
J 0
(-2025 5575);
DISPLAY 0.489362 (-2025 5575);
PAINT RED (-2025 5575);
FORCEPROP 2 LAST CDS_LIB pure_quanta
J 2
(-2050 5625);
DISPLAY INVISIBLE (-2050 5625);
FORCEPROP 1 LAST PATH I97
J 2
(-2100 5800);
DISPLAY 0.978723 (-2100 5800);
PAINT WHITE (-2100 5800);
DISPLAY INVISIBLE (-2100 5800);
FORCEPROP 1 LAST WATTAGE 1/16W
J 2
(-2100 5625);
DISPLAY 0.489362 (-2100 5625);
PAINT SKYBLUE (-2100 5625);
DISPLAY INVISIBLE (-2100 5625);
FORCEPROP 1 LAST PART_NUMBER TMP_QCS21002JB34
J 2
(-2100 5550);
DISPLAY 0.489362 (-2100 5550);
PAINT SKYBLUE (-2100 5550);
DISPLAY INVISIBLE (-2100 5550);
FORCEPROP 1 LAST PACK_TYPE 0402LF
J 2
(-2100 5575);
DISPLAY 0.489362 (-2100 5575);
PAINT SKYBLUE (-2100 5575);
DISPLAY INVISIBLE (-2100 5575);
FORCEADD OFFPAGE..2
R 2
(-3125 5400);
FORCEPROP 2 LAST $XR1 117 
J 0
(-3499 5400);
DISPLAY 0.638298 (-3499 5400);
PAINT MONO (-3499 5400);
FORCEPROP 2 LAST $XR0 76 
J 0
(-3379 5400);
DISPLAY 0.638298 (-3379 5400);
PAINT MONO (-3379 5400);
FORCEPROP 2 LAST CDS_LIB standard
J 2
(-3125 5400);
DISPLAY INVISIBLE (-3125 5400);
FORCEPROP 1 LAST OFFPAGE TRUE
J 2
(-3450 5275);
DISPLAY 0.872340 (-3450 5275);
PAINT GREEN (-3450 5275);
DISPLAY INVISIBLE (-3450 5275);
FORCEPROP 1 LAST COMMENT_BODY TRUE
J 2
(-3080 5305);
DISPLAY 0.872340 (-3080 5305);
PAINT PEACH (-3080 5305);
DISPLAY INVISIBLE (-3080 5305);
FORCEPROP 2 LAST PATH I99
J 0
(-3375 5450);
DISPLAY 1.021277 (-3375 5450);
DISPLAY INVISIBLE (-3375 5450);
FORCEADD DNS..2
(-9100 5900);
PAINT RED (-9100 5900);
FORCEPROP 1 LAST COMMENT_BODY TRUE
R 1
J 0
(-9025 5675);
DISPLAY 0.872340 (-9025 5675);
PAINT GREEN (-9025 5675);
DISPLAY INVISIBLE (-9025 5675);
FORCEPROP 2 LAST CDS_LIB mstr_misc
J 0
(-9100 5900);
DISPLAY INVISIBLE (-9100 5900);
FORCEADD DNS..2
(-8550 5900);
PAINT RED (-8550 5900);
FORCEPROP 1 LAST COMMENT_BODY TRUE
R 1
J 0
(-8475 5675);
DISPLAY 0.872340 (-8475 5675);
PAINT GREEN (-8475 5675);
DISPLAY INVISIBLE (-8475 5675);
FORCEPROP 2 LAST CDS_LIB mstr_misc
J 0
(-8550 5900);
DISPLAY INVISIBLE (-8550 5900);
FORCEADD DNS..2
(-1525 5650);
PAINT RED (-1525 5650);
FORCEPROP 1 LAST COMMENT_BODY TRUE
R 1
J 0
(-1450 5425);
DISPLAY 0.872340 (-1450 5425);
PAINT GREEN (-1450 5425);
DISPLAY INVISIBLE (-1450 5425);
FORCEPROP 2 LAST CDS_LIB mstr_misc
J 0
(-1525 5650);
DISPLAY INVISIBLE (-1525 5650);
FORCEADD DNS..2
(-1000 5625);
PAINT RED (-1000 5625);
FORCEPROP 1 LAST COMMENT_BODY TRUE
R 1
J 0
(-925 5400);
DISPLAY 0.872340 (-925 5400);
PAINT GREEN (-925 5400);
DISPLAY INVISIBLE (-925 5400);
FORCEPROP 2 LAST CDS_LIB mstr_misc
J 0
(-1000 5625);
DISPLAY INVISIBLE (-1000 5625);
FORCEADD DNS..2
(-1875 5650);
PAINT RED (-1875 5650);
FORCEPROP 1 LAST COMMENT_BODY TRUE
R 1
J 0
(-1800 5425);
DISPLAY 0.872340 (-1800 5425);
PAINT GREEN (-1800 5425);
DISPLAY INVISIBLE (-1800 5425);
FORCEPROP 2 LAST CDS_LIB mstr_misc
J 0
(-1875 5650);
DISPLAY INVISIBLE (-1875 5650);
FORCEADD DNS..2
(-1350 5650);
PAINT RED (-1350 5650);
FORCEPROP 2 LAST CDS_LIB mstr_misc
J 0
(-1350 5650);
DISPLAY INVISIBLE (-1350 5650);
FORCEPROP 1 LAST COMMENT_BODY TRUE
R 1
J 0
(-1275 5425);
DISPLAY 0.872340 (-1275 5425);
PAINT GREEN (-1275 5425);
DISPLAY INVISIBLE (-1275 5425);
FORCEADD DNS..2
(-1725 5650);
PAINT RED (-1725 5650);
FORCEPROP 1 LAST COMMENT_BODY TRUE
R 1
J 0
(-1650 5425);
DISPLAY 0.872340 (-1650 5425);
PAINT GREEN (-1650 5425);
DISPLAY INVISIBLE (-1650 5425);
FORCEPROP 2 LAST CDS_LIB mstr_misc
J 0
(-1725 5650);
DISPLAY INVISIBLE (-1725 5650);
FORCEADD DNS..2
(-8750 5900);
PAINT RED (-8750 5900);
FORCEPROP 1 LAST COMMENT_BODY TRUE
R 1
J 0
(-8675 5675);
DISPLAY 0.872340 (-8675 5675);
PAINT GREEN (-8675 5675);
DISPLAY INVISIBLE (-8675 5675);
FORCEPROP 2 LAST CDS_LIB mstr_misc
J 0
(-8750 5900);
DISPLAY INVISIBLE (-8750 5900);
FORCEADD DNS..2
(-2050 5650);
PAINT RED (-2050 5650);
FORCEPROP 2 LAST CDS_LIB mstr_misc
J 0
(-2050 5650);
DISPLAY INVISIBLE (-2050 5650);
FORCEPROP 1 LAST COMMENT_BODY TRUE
R 1
J 0
(-1975 5425);
DISPLAY 0.872340 (-1975 5425);
PAINT GREEN (-1975 5425);
DISPLAY INVISIBLE (-1975 5425);
FORCEADD QUANTA_TITLE_BLOCK_C..1
(0 0);
FORCEPROP 0 LAST CDS_CON_LAST_MODIFIED Fri Mar 11 14:52:48 2022
J 0
(-1885 15);
DISPLAY INVISIBLE (-1885 15);
FORCEPROP 1 LAST CUSTOM_TXT_CDS <CON_LAST_MODIFIED>
J 0
(-1885 15);
DISPLAY 0.978723 (-1885 15);
FORCEPROP 2 LAST CUSTOM_TXT_CDS <XR_PAGE_TITLE>
J 0
(-7890 5250);
DISPLAY 0.638298 (-7890 5250);
PAINT PINK (-7890 5250);
DISPLAY INVISIBLE (-7890 5250);
FORCEPROP 1 LAST CUSTOM_TXT_CDS <NAME_2>
J 0
(-3175 50);
FORCEPROP 1 LAST CUSTOM_TXT_CDS <NAME_1>
J 0
(-3175 175);
FORCEPROP 1 LAST CUSTOM_TXT_CDS <Q_NUMBER>
J 0
(-1403 103);
DISPLAY 1.212766 (-1403 103);
FORCEPROP 1 LAST CUSTOM_TXT_CDS <Q_PROJ>
J 0
(-2382 102);
DISPLAY 1.212766 (-2382 102);
FORCEPROP 1 LAST CUSTOM_TXT_CDS <Q_REV>
J 0
(-184 103);
DISPLAY 1.212766 (-184 103);
FORCEPROP 1 LAST CUSTOM_TXT_CDS <CON_PAGE_NUM> OF <CON_TOTAL_PAGES>
J 0
(-446 18);
DISPLAY 0.978723 (-446 18);
FORCEPROP 1 LAST Q_TITLE CPU SPI LEVEL SHIFT
J 0
(-9300 50);
DISPLAY 2.446809 (-9300 50);
PAINT GREEN (-9300 50);
FORCEPROP 1 LAST Q_DEPT BU9
J 1
(-3763 49);
DISPLAY 1.957447 (-3763 49);
PAINT GREEN (-3763 49);
FORCEPROP 2 LAST CDS_LIB pure_quanta
J 0
(0 0);
DISPLAY INVISIBLE (0 0);
FORCEPROP 1 LAST CDS_LMAN_SYM_OUTLINE -9475,6775,100,-125
J 0
(0 0);
DISPLAY 0.468085 (0 0);
PAINT GREEN (0 0);
DISPLAY INVISIBLE (0 0);
FORCEPROP 2 LAST PAGE_BORDER TRUE
J 0
(-7890 5250);
DISPLAY 0.638298 (-7890 5250);
PAINT PINK (-7890 5250);
DISPLAY INVISIBLE (-7890 5250);
FORCEPROP 1 LAST COMMENT_BODY TRUE
J 0
(12 -13);
DISPLAY 0.978723 (12 -13);
PAINT GREEN (12 -13);
DISPLAY INVISIBLE (12 -13);
FORCEPROP 2 LAST CDS_XR_PAGE_TITLE CR-76 : @T6G_MB_LIB.T6G(SCH_1):PAGE76
J 0
(-7890 5250);
DISPLAY 0.638298 (-7890 5250);
PAINT PINK (-7890 5250);
DISPLAY INVISIBLE (-7890 5250);
FORCEADD DNS..2
(-8925 5900);
PAINT RED (-8925 5900);
FORCEPROP 1 LAST COMMENT_BODY TRUE
R 1
J 0
(-8850 5675);
DISPLAY 0.872340 (-8850 5675);
PAINT GREEN (-8850 5675);
DISPLAY INVISIBLE (-8850 5675);
FORCEPROP 2 LAST CDS_LIB mstr_misc
J 0
(-8925 5900);
DISPLAY INVISIBLE (-8925 5900);
WIRE 16 -1 (-6200 2575)(-6200 2550);
WIRE 16 -1 (-4725 2550)(-4725 2500);
WIRE 16 -1 (-4750 4600)(-4750 4650);
WIRE 16 -1 (-6100 4600)(-6100 4650);
WIRE 16 -1 (-4775 3775)(-4775 3600);
WIRE 16 -1 (-5025 3775)(-4775 3775);
WIRE 16 -1 (-5150 2125)(-4825 2125);
WIRE 16 -1 (-4825 2125)(-4825 1750);
WIRE 16 -1 (-6875 2125)(-5950 2125);
FORCEPROP 2 LAST SIG_NAME ROM_LS_EN
J 0
(-6685 2135);
DISPLAY 0.489362 (-6685 2135);
WIRE 16 -1 (-8025 6000)(-8025 6025);
WIRE 16 -1 (-8025 5975)(-8025 6000);
WIRE 16 -1 (-8200 6000)(-8025 6000);
WIRE 16 -1 (-8200 6000)(-8200 5975);
WIRE 16 -1 (-8375 6000)(-8200 6000);
WIRE 16 -1 (-8375 5975)(-8375 6000);
WIRE 16 -1 (-8375 6000)(-8550 6000);
WIRE 16 -1 (-8550 6000)(-8550 5975);
WIRE 16 -1 (-8550 6000)(-8725 6000);
WIRE 16 -1 (-8725 6000)(-8725 5975);
WIRE 16 -1 (-8725 6000)(-8900 6000);
WIRE 16 -1 (-8900 6000)(-8900 5975);
WIRE 16 -1 (-8900 6000)(-9075 6000);
WIRE 16 -1 (-9075 6000)(-9075 5975);
WIRE 16 -1 (-9250 6000)(-9075 6000);
WIRE 16 -1 (-9250 6000)(-9250 5975);
WIRE 16 -1 (-6225 4050)(-6225 4025);
WIRE 16 -1 (-5825 4025)(-6225 4025);
WIRE 16 -1 (-6225 4025)(-6225 3975);
WIRE 16 -1 (-5825 3975)(-6225 3975);
WIRE 16 -1 (-6225 3975)(-6225 3925);
WIRE 16 -1 (-6225 3925)(-5825 3925);
WIRE 16 -1 (-6225 3925)(-6225 3875);
WIRE 16 -1 (-5825 3875)(-6225 3875);
WIRE 16 -1 (-5025 4525)(-4875 4525);
WIRE 16 -1 (-4875 4525)(-4875 4900);
WIRE 16 -1 (-4750 4900)(-4875 4900);
WIRE 16 -1 (-4875 4900)(-4875 4950);
WIRE 16 -1 (-4750 4850)(-4750 4900);
WIRE 16 -1 (-6100 4850)(-6100 4900);
WIRE 16 -1 (-6100 4900)(-5975 4900);
WIRE 16 -1 (-5975 4900)(-5975 4925);
WIRE 16 -1 (-5975 4525)(-5975 4900);
WIRE 16 -1 (-5975 4525)(-5825 4525);
WIRE 16 -1 (-4725 2750)(-4725 2800);
WIRE 16 -1 (-4725 2800)(-4850 2800);
WIRE 16 -1 (-4850 2800)(-4850 2850);
WIRE 16 -1 (-4850 2475)(-4850 2800);
WIRE 16 -1 (-5150 2475)(-4850 2475);
WIRE 16 -1 (-6075 2475)(-6075 2825);
WIRE 16 -1 (-6075 2475)(-5950 2475);
WIRE 16 -1 (-6075 2825)(-6075 2850);
WIRE 16 -1 (-6200 2825)(-6075 2825);
WIRE 16 -1 (-6200 2775)(-6200 2825);
WIRE 16 -1 (-2225 5725)(-2225 5775);
WIRE 16 -1 (-2225 5775)(-2050 5775);
WIRE 16 -1 (-2225 5875)(-2225 5775);
WIRE 16 -1 (-2050 5775)(-1875 5775);
WIRE 16 -1 (-2050 5725)(-2050 5775);
WIRE 16 -1 (-1875 5775)(-1700 5775);
WIRE 16 -1 (-1875 5725)(-1875 5775);
WIRE 16 -1 (-1700 5775)(-1525 5775);
WIRE 16 -1 (-1700 5725)(-1700 5775);
WIRE 16 -1 (-1525 5775)(-1350 5775);
WIRE 16 -1 (-1525 5725)(-1525 5775);
WIRE 16 -1 (-1350 5775)(-1175 5775);
WIRE 16 -1 (-1350 5725)(-1350 5775);
WIRE 16 -1 (-1175 5775)(-1025 5775);
WIRE 16 -1 (-1175 5775)(-1175 5725);
WIRE 16 -1 (-1025 5775)(-1025 5725);
WIRE 16 -1 (-5950 2325)(-6875 2325);
FORCEPROP 2 LAST SIG_NAME SPI_CPU0_D2
J 0
(-6685 2335);
DISPLAY 0.489362 (-6685 2335);
WIRE 16 -1 (-6875 2275)(-5950 2275);
FORCEPROP 2 LAST SIG_NAME SPI_CPU0_D0
J 0
(-6685 2285);
DISPLAY 0.489362 (-6685 2285);
WIRE 16 -1 (-6875 2225)(-5950 2225);
FORCEPROP 2 LAST SIG_NAME SPI_CPU0_D1
J 0
(-6685 2235);
DISPLAY 0.489362 (-6685 2235);
WIRE 16 -1 (-5950 2375)(-6875 2375);
FORCEPROP 2 LAST SIG_NAME SPI_CPU0_D3
J 0
(-6685 2385);
DISPLAY 0.489362 (-6685 2385);
WIRE 16 -1 (-9250 5775)(-9250 5225);
WIRE 16 -1 (-9250 5225)(-7150 5225);
FORCEPROP 2 LAST SIG_NAME ROM_LS_EN
J 0
(-7810 5235);
DISPLAY 0.446809 (-7810 5235);
WIRE 16 -1 (-5025 4175)(-4050 4175);
FORCEPROP 2 LAST SIG_NAME SPI_CPU0_LVC3_R_TPM_CS_N
J 0
(-4785 4185);
DISPLAY 0.489362 (-4785 4185);
FORCEPROP 2 LASTPROP $XRERR UNIQUE?
J 0
(-5025 4185);
DISPLAY 0.638298 (-5025 4185);
PAINT MONO (-5025 4185);
DISPLAY INVISIBLE (-5025 4185);
WIRE 16 -1 (-4050 4225)(-5025 4225);
FORCEPROP 2 LAST SIG_NAME SPI_CPU0_LVC3_CS1_N
J 0
(-4785 4225);
DISPLAY 0.489362 (-4785 4225);
FORCEPROP 2 LASTPROP $XRERR UNIQUE?
J 0
(-5025 4225);
DISPLAY 0.638298 (-5025 4225);
PAINT MONO (-5025 4225);
DISPLAY INVISIBLE (-5025 4225);
WIRE 16 -1 (-5825 3825)(-6750 3825);
FORCEPROP 2 LAST SIG_NAME ROM_SD_LS_OE
J 0
(-6560 3835);
DISPLAY 0.446809 (-6560 3835);
WIRE 16 -1 (-5025 4275)(-4050 4275);
FORCEPROP 2 LAST SIG_NAME SPI_CPU0_LVC3_CLK
J 0
(-4785 4275);
DISPLAY 0.489362 (-4785 4275);
FORCEPROP 2 LASTPROP $XRERR UNIQUE?
J 0
(-5025 4275);
DISPLAY 0.638298 (-5025 4275);
PAINT MONO (-5025 4275);
DISPLAY INVISIBLE (-5025 4275);
WIRE 16 -1 (-5025 4325)(-4050 4325);
FORCEPROP 2 LAST SIG_NAME SPI_CPU0_LVC3_CS0_N
J 0
(-4785 4325);
DISPLAY 0.489362 (-4785 4325);
FORCEPROP 2 LASTPROP $XRERR UNIQUE?
J 0
(-5025 4325);
DISPLAY 0.638298 (-5025 4325);
PAINT MONO (-5025 4325);
DISPLAY INVISIBLE (-5025 4325);
WIRE 16 -1 (-6750 4275)(-5825 4275);
FORCEPROP 2 LAST SIG_NAME SPI_CPU0_CLK
J 0
(-6560 4285);
DISPLAY 0.489362 (-6560 4285);
WIRE 16 -1 (-6750 4325)(-5825 4325);
FORCEPROP 2 LAST SIG_NAME SPI_CPU0_CS0_N
J 0
(-6560 4335);
DISPLAY 0.489362 (-6560 4335);
WIRE 16 -1 (-5825 4225)(-6750 4225);
FORCEPROP 2 LAST SIG_NAME SPI_CPU0_CS1_N
J 0
(-6560 4235);
DISPLAY 0.489362 (-6560 4235);
WIRE 16 -1 (-6750 4175)(-5825 4175);
FORCEPROP 2 LAST SIG_NAME SPI_CPU0_TPM_CS_N
J 0
(-6560 4185);
DISPLAY 0.489362 (-6560 4185);
WIRE 16 -1 (-3850 4275)(-3050 4275);
FORCEPROP 2 LAST SIG_NAME SPI_CPU0_LVC3_SCM_CLK
J 0
(-3710 4285);
DISPLAY 0.489362 (-3710 4285);
WIRE 16 -1 (-3050 4325)(-3850 4325);
FORCEPROP 2 LAST SIG_NAME SPI_CPU0_LVC3_SCM_CS0_N
J 0
(-3710 4335);
DISPLAY 0.489362 (-3710 4335);
WIRE 16 -1 (-3050 4225)(-3850 4225);
FORCEPROP 2 LAST SIG_NAME SPI_CPU0_LVC3_SCM_CS1_N
J 0
(-3710 4235);
DISPLAY 0.489362 (-3710 4235);
WIRE 16 -1 (-3850 4175)(-3050 4175);
FORCEPROP 2 LAST SIG_NAME SPI_CPU0_LVC3_TPM_CS_N
J 0
(-3700 4185);
DISPLAY 0.489362 (-3700 4185);
WIRE 16 -1 (-5150 2225)(-4175 2225);
FORCEPROP 2 LAST SIG_NAME SPI_CPU0_LVC3_D1
J 0
(-4910 2225);
DISPLAY 0.489362 (-4910 2225);
FORCEPROP 2 LASTPROP $XRERR UNIQUE?
J 0
(-5150 2225);
DISPLAY 0.638298 (-5150 2225);
PAINT MONO (-5150 2225);
DISPLAY INVISIBLE (-5150 2225);
WIRE 16 -1 (-5150 2275)(-4175 2275);
FORCEPROP 2 LAST SIG_NAME SPI_CPU0_LVC3_D0
J 0
(-4910 2275);
DISPLAY 0.489362 (-4910 2275);
FORCEPROP 2 LASTPROP $XRERR UNIQUE?
J 0
(-5150 2275);
DISPLAY 0.638298 (-5150 2275);
PAINT MONO (-5150 2275);
DISPLAY INVISIBLE (-5150 2275);
WIRE 16 -1 (-3975 2275)(-3175 2275);
FORCEPROP 2 LAST SIG_NAME SPI_CPU0_LVC3_SCM_D0
J 0
(-3835 2285);
DISPLAY 0.489362 (-3835 2285);
WIRE 16 -1 (-3975 2225)(-3175 2225);
FORCEPROP 2 LAST SIG_NAME SPI_CPU0_LVC3_SCM_D1
J 0
(-3835 2235);
DISPLAY 0.489362 (-3835 2235);
WIRE 16 -1 (-4175 2325)(-5150 2325);
FORCEPROP 2 LAST SIG_NAME SPI_CPU0_LVC3_D2
J 0
(-4910 2335);
DISPLAY 0.489362 (-4910 2335);
FORCEPROP 2 LASTPROP $XRERR UNIQUE?
J 0
(-5150 2335);
DISPLAY 0.638298 (-5150 2335);
PAINT MONO (-5150 2335);
DISPLAY INVISIBLE (-5150 2335);
WIRE 16 -1 (-3175 2325)(-3975 2325);
FORCEPROP 2 LAST SIG_NAME SPI_CPU0_LVC3_SCM_D2
J 0
(-3825 2335);
DISPLAY 0.489362 (-3825 2335);
WIRE 16 -1 (-4175 2375)(-5150 2375);
FORCEPROP 2 LAST SIG_NAME SPI_CPU0_LVC3_D3
J 0
(-4910 2385);
DISPLAY 0.489362 (-4910 2385);
FORCEPROP 2 LASTPROP $XRERR UNIQUE?
J 0
(-5150 2385);
DISPLAY 0.638298 (-5150 2385);
PAINT MONO (-5150 2385);
DISPLAY INVISIBLE (-5150 2385);
WIRE 16 -1 (-3175 2375)(-3975 2375);
FORCEPROP 2 LAST SIG_NAME SPI_CPU0_LVC3_SCM_D3
J 0
(-3825 2385);
DISPLAY 0.489362 (-3825 2385);
WIRE 16 -1 (-7150 5275)(-9075 5275);
FORCEPROP 2 LAST SIG_NAME SPI_CPU0_D3
J 0
(-7825 5285);
DISPLAY 0.489362 (-7825 5285);
WIRE 16 -1 (-9075 5275)(-9075 5775);
WIRE 16 -1 (-7150 5325)(-8900 5325);
FORCEPROP 2 LAST SIG_NAME SPI_CPU0_D2
J 0
(-7825 5335);
DISPLAY 0.489362 (-7825 5335);
WIRE 16 -1 (-8900 5325)(-8900 5775);
WIRE 16 -1 (-7150 5375)(-8725 5375);
FORCEPROP 2 LAST SIG_NAME SPI_CPU0_D1
J 0
(-7825 5385);
DISPLAY 0.489362 (-7825 5385);
WIRE 16 -1 (-8725 5375)(-8725 5775);
WIRE 16 -1 (-7150 5425)(-8550 5425);
FORCEPROP 2 LAST SIG_NAME SPI_CPU0_D0
J 0
(-7825 5435);
DISPLAY 0.489362 (-7825 5435);
WIRE 16 -1 (-8550 5775)(-8550 5425);
WIRE 16 -1 (-8200 5775)(-8200 5525);
WIRE 16 -1 (-8200 5525)(-7150 5525);
FORCEPROP 2 LAST SIG_NAME SPI_CPU0_TPM_CS_N
J 0
(-7825 5535);
DISPLAY 0.489362 (-7825 5535);
WIRE 16 -1 (-7150 5475)(-8375 5475);
FORCEPROP 2 LAST SIG_NAME SPI_CPU0_CS1_N
J 0
(-7825 5485);
DISPLAY 0.489362 (-7825 5485);
WIRE 16 -1 (-8375 5775)(-8375 5475);
WIRE 16 -1 (-7150 5575)(-8025 5575);
FORCEPROP 2 LAST SIG_NAME SPI_CPU0_CS0_N
J 0
(-7825 5585);
DISPLAY 0.489362 (-7825 5585);
WIRE 16 -1 (-8025 5775)(-8025 5575);
WIRE 16 -1 (-2225 5525)(-2225 5450);
WIRE 16 -1 (-2225 5450)(-3075 5450);
FORCEPROP 2 LAST SIG_NAME SPI_CPU0_LVC3_SCM_CLK
J 0
(-3000 5460);
DISPLAY 0.489362 (-3000 5460);
WIRE 16 -1 (-2050 5525)(-2050 5400);
WIRE 16 -1 (-2050 5400)(-3075 5400);
FORCEPROP 2 LAST SIG_NAME SPI_CPU0_LVC3_SCM_CS0_N
J 0
(-3000 5410);
DISPLAY 0.489362 (-3000 5410);
WIRE 16 -1 (-3075 5350)(-1875 5350);
FORCEPROP 2 LAST SIG_NAME SPI_CPU0_LVC3_SCM_D0
J 0
(-3000 5360);
DISPLAY 0.489362 (-3000 5360);
WIRE 16 -1 (-1875 5525)(-1875 5350);
WIRE 16 -1 (-3075 5300)(-1700 5300);
FORCEPROP 2 LAST SIG_NAME SPI_CPU0_LVC3_SCM_D1
J 0
(-3000 5310);
DISPLAY 0.489362 (-3000 5310);
WIRE 16 -1 (-1700 5525)(-1700 5300);
WIRE 16 -1 (-3075 5250)(-1525 5250);
FORCEPROP 2 LAST SIG_NAME SPI_CPU0_LVC3_SCM_D2
J 0
(-3000 5260);
DISPLAY 0.489362 (-3000 5260);
WIRE 16 -1 (-1525 5525)(-1525 5250);
WIRE 16 -1 (-3075 5150)(-1175 5150);
FORCEPROP 2 LAST SIG_NAME SPI_CPU0_LVC3_TPM_CS_N
J 0
(-3010 5160);
DISPLAY 0.446809 (-3010 5160);
WIRE 16 -1 (-1175 5525)(-1175 5150);
WIRE 16 -1 (-3075 5200)(-1350 5200);
FORCEPROP 2 LAST SIG_NAME SPI_CPU0_LVC3_SCM_D3
J 0
(-3000 5210);
DISPLAY 0.489362 (-3000 5210);
WIRE 16 -1 (-1350 5525)(-1350 5200);
WIRE 16 -1 (-1025 5525)(-1025 5100);
WIRE 16 -1 (-1025 5100)(-3075 5100);
FORCEPROP 2 LAST SIG_NAME SPI_CPU0_LVC3_SCM_CS1_N
J 0
(-3010 5110);
DISPLAY 0.446809 (-3010 5110);
DOT 1 (-6225 3925);
DOT 1 (-5975 4900);
DOT 1 (-1175 5775);
DOT 1 (-6075 2825);
DOT 1 (-4875 4900);
DOT 1 (-4850 2800);
DOT 1 (-8900 6000);
DOT 1 (-8725 6000);
DOT 1 (-8025 6000);
DOT 1 (-1525 5775);
DOT 1 (-2225 5775);
DOT 1 (-1350 5775);
DOT 1 (-8375 6000);
DOT 1 (-9075 6000);
DOT 1 (-8200 6000);
DOT 1 (-8550 6000);
DOT 1 (-1700 5775);
DOT 1 (-1875 5775);
DOT 1 (-2050 5775);
DOT 1 (-6225 4025);
DOT 1 (-6225 3975);
FORCENOTE
CPU0 QSPI0 TO SCM QSPI0
(-6525 3225) 0;
DISPLAY LEFT (-6525 3225);
DISPLAY 2.000000 (-6525 3225);
PAINT WHITE (-6525 3225);
QUIT
